G04 ================== begin FILE IDENTIFICATION RECORD ==================*
G04 Layout Name:  9048_F0T_Management_Board_D_brd_V04_1213_1625.brd*
G04 Film Name:    pmb*
G04 File Format:  Gerber RS274X*
G04 File Origin:  Cadence Allegro 17.2-S081*
G04 Origin Date:  Tue Dec 13 16:31:10 2022*
G04 *
G04 Layer:  DRAWING FORMAT/TITLE_BLOCK_A*
G04 Layer:  VIA CLASS/PASTEMASK_BOTTOM*
G04 Layer:  PIN/PASTEMASK_BOTTOM*
G04 Layer:  PACKAGE GEOMETRY/PASTEMASK_BOTTOM*
G04 Layer:  MANUFACTURING/PHOTOPLOT_OUTLINE*
G04 Layer:  DRAWING FORMAT/TITLE_BLOCK*
G04 Layer:  DRAWING FORMAT/TITLE_DATA_PMB*
G04 *
G04 Offset:    (0.00 0.00)*
G04 Mirror:    No*
G04 Mode:      Positive*
G04 Rotation:  0*
G04 FullContactRelief:  No*
G04 UndefLineWidth:     6.00*
G04 ================== end FILE IDENTIFICATION RECORD ====================*
%FSLAX25Y25*MOIN*%
%IR0*IPPOS*OFA0.00000B0.00000*MIA0B0*SFA1.00000B1.00000*%
%AMMACRO60*
4,1,48,-.05512,-.01476,
.05512,-.01476,
.05512,.01476,
-.05512,.01476,
-.05512,.00295,
-.04331,.00295,
-.04331,.00976,
-.03543,.00976,
-.03543,.00295,
-.02362,.00295,
-.02362,.00976,
-.01575,.00976,
-.01575,.00295,
-.00394,.00295,
-.00394,.00976,
.00394,.00976,
.00394,.00295,
.01575,.00295,
.01575,.00976,
.02362,.00976,
.02362,.00295,
.03543,.00295,
.03543,.00976,
.04331,.00976,
.04331,.00295,
.05012,.00295,
.05012,-.00295,
.04331,-.00295,
.04331,-.00976,
.03543,-.00976,
.03543,-.00295,
.02362,-.00295,
.02362,-.00976,
.01575,-.00976,
.01575,-.00295,
.00394,-.00295,
.00394,-.00976,
-.00394,-.00976,
-.00394,-.00295,
-.01575,-.00295,
-.01575,-.00976,
-.02362,-.00976,
-.02362,-.00295,
-.03543,-.00295,
-.03543,-.00976,
-.04331,-.00976,
-.04331,-.00295,
-.05512,-.00295,
-.05512,-.01476,
0.0*
%
%ADD60MACRO60*%
%ADD65C,.02*%
%ADD19C,.061*%
%ADD55C,.044*%
%ADD14C,.026*%
%ADD31C,.018*%
%ADD56C,.028*%
%ADD35C,.048*%
%ADD15C,.039*%
%ADD20R,.061X.061*%
%ADD57R,.044X.044*%
%ADD26R,.048X.048*%
%AMMACRO45*
4,1,28,-.00492,.00566,
-.00659,.00733,
-.00269,.01122,
-.002174,.011659,
-.001588,.011998,
-.000951,.01223,
-.000284,.012348,
.000393,.012348,
.001061,.012231,
.001697,.012,
.002284,.011661,
.002803,.011226,
.00284,.01119,
.01119,.00284,
.011631,.002326,
.011978,.001744,
.012217,.00111,
.012343,.000444,
.012352,-.000233,
.012243,-.000902,
.012019,-.001541,
.011688,-.002132,
.011259,-.002656,
.01122,-.00269,
.00733,-.00659,
.00566,-.00492,
-.00172,-.0123,
-.0123,-.00172,
-.00492,.00566,
0.0*
%
%ADD45MACRO45*%
%AMMACRO24*
4,1,28,-.00748,.00052,
-.00984,.00052,
-.00984,.00603,
-.009782,.006705,
-.009607,.007359,
-.009321,.007974,
-.008933,.008529,
-.008455,.009009,
-.0079,.009398,
-.007286,.009685,
-.006632,.009861,
-.005957,.00992,
-.00591,.00992,
.00591,.00992,
.006585,.009869,
.007242,.009701,
.007859,.009421,
.008418,.009039,
.008903,.008565,
.009297,.008015,
.009591,.007404,
.009773,.006751,
.00984,.006077,
.00984,.00603,
.00984,.00052,
.00748,.00052,
.00748,-.00991,
-.00748,-.00991,
-.00748,.00052,
0.0*
%
%ADD24MACRO24*%
%AMMACRO16*
4,1,28,.00052,.00748,
.00052,.00984,
.00603,.00984,
.006705,.009782,
.007359,.009607,
.007974,.009321,
.008529,.008933,
.009009,.008455,
.009398,.0079,
.009685,.007286,
.009861,.006632,
.00992,.005957,
.00992,.00591,
.00992,-.00591,
.009869,-.006585,
.009701,-.007242,
.009421,-.007859,
.009039,-.008418,
.008565,-.008903,
.008015,-.009297,
.007404,-.009591,
.006751,-.009773,
.006077,-.00984,
.00603,-.00984,
.00052,-.00984,
.00052,-.00748,
-.00991,-.00748,
-.00991,.00748,
.00052,.00748,
0.0*
%
%ADD16MACRO16*%
%AMMACRO40*
4,1,8,.0034,.0082,
-.0034,.0082,
-.0082,.0034,
-.0082,-.00341,
-.00341,-.0082,
.0034,-.0082,
.0082,-.0034,
.0082,.0034,
.0034,.0082,
0.0*
%
%ADD40MACRO40*%
%AMMACRO42*
4,1,8,.0082,-.0034,
.0082,.0034,
.0034,.0082,
-.00341,.0082,
-.0082,.00341,
-.0082,-.0034,
-.0034,-.0082,
.0034,-.0082,
.0082,-.0034,
0.0*
%
%ADD42MACRO42*%
%AMMACRO43*
4,1,28,-.00565,.00493,
-.00732,.0066,
-.01121,.0027,
-.011649,.002185,
-.011989,.001599,
-.012222,.000962,
-.01234,.000295,
-.012342,-.000382,
-.012225,-.001049,
-.011994,-.001686,
-.011657,-.002273,
-.011222,-.002793,
-.01119,-.00283,
-.00283,-.01119,
-.002313,-.011629,
-.00173,-.011974,
-.001096,-.012212,
-.00043,-.012337,
.000247,-.012344,
.000915,-.012234,
.001554,-.012009,
.002145,-.011677,
.002668,-.011247,
.0027,-.01121,
.0066,-.00732,
.00493,-.00565,
.0123,.00173,
.00173,.0123,
-.00565,.00493,
0.0*
%
%ADD43MACRO43*%
%AMMACRO23*
4,1,28,-.00748,-.00051,
-.00984,-.00051,
-.00984,-.00602,
-.009782,-.006695,
-.009607,-.007349,
-.009321,-.007964,
-.008933,-.008519,
-.008455,-.008998,
-.0079,-.009388,
-.007287,-.009675,
-.006632,-.009851,
-.005958,-.00991,
-.00591,-.00991,
.00591,-.00991,
.006585,-.009859,
.007242,-.009691,
.007859,-.009411,
.008418,-.009029,
.008903,-.008555,
.009297,-.008005,
.00959,-.007394,
.009773,-.006742,
.00984,-.006068,
.00984,-.00602,
.00984,-.00051,
.00748,-.00051,
.00748,.00992,
-.00748,.00992,
-.00748,-.00051,
0.0*
%
%ADD23MACRO23*%
%AMMACRO11*
4,1,28,-.00051,.00748,
-.00051,.00984,
-.00602,.00984,
-.006695,.009782,
-.007349,.009607,
-.007964,.009321,
-.008519,.008933,
-.008998,.008455,
-.009388,.0079,
-.009675,.007287,
-.009851,.006632,
-.00991,.005958,
-.00991,.00591,
-.00991,-.00591,
-.009859,-.006585,
-.009691,-.007242,
-.009411,-.007859,
-.009029,-.008418,
-.008555,-.008903,
-.008005,-.009297,
-.007394,-.00959,
-.006742,-.009773,
-.006068,-.00984,
-.00602,-.00984,
-.00051,-.00984,
-.00051,-.00748,
.00992,-.00748,
.00992,.00748,
-.00051,.00748,
0.0*
%
%ADD11MACRO11*%
%ADD54R,.02X.02*%
%ADD69R,.05X.04*%
%ADD63R,.032X.022*%
%ADD61R,.026X.011*%
%ADD18R,.04X.05*%
%ADD59R,.011X.026*%
%ADD46R,.04X.025*%
%ADD47R,.071X.04*%
%ADD64R,.036X.032*%
%ADD53R,.016X.024*%
%ADD51C,.131*%
%ADD49R,.014X.044*%
%ADD17R,.024X.017*%
%ADD68R,.013X.046*%
%ADD67R,.07X.017*%
%ADD66R,.032X.036*%
%ADD52R,.028X.04*%
%ADD50R,.032X.028*%
%AMMACRO34*
21,1,.028,.032,0.0,0.0,45.*%
%ADD34MACRO34*%
%ADD27R,.017X.024*%
%ADD58R,.048X.04*%
%ADD44R,.028X.032*%
%ADD37R,.046X.034*%
%ADD36R,.054X.044*%
%ADD41C,.315*%
%ADD25R,.026X.054*%
%ADD62R,.059X.014*%
%ADD28R,.014X.059*%
%ADD10C,.256*%
%ADD48R,.048X.039*%
%AMMACRO33*
4,1,28,-.00566,-.00492,
-.00733,-.00659,
-.01122,-.00269,
-.011659,-.002174,
-.011998,-.001588,
-.01223,-.000951,
-.012348,-.000284,
-.012348,.000393,
-.012231,.001061,
-.012,.001697,
-.011661,.002284,
-.011226,.002803,
-.01119,.00284,
-.00284,.01119,
-.002326,.011631,
-.001744,.011978,
-.00111,.012217,
-.000444,.012343,
.000233,.012352,
.000902,.012243,
.001541,.012019,
.002132,.011688,
.002656,.011259,
.00269,.01122,
.00659,.00733,
.00492,.00566,
.0123,-.00172,
.00172,-.0123,
-.00566,-.00492,
0.0*
%
%ADD33MACRO33*%
%AMMACRO30*
4,1,28,.00492,-.00566,
.00659,-.00733,
.00269,-.01122,
.002174,-.011659,
.001588,-.011998,
.000951,-.01223,
.000284,-.012348,
-.000393,-.012348,
-.001061,-.012231,
-.001697,-.012,
-.002284,-.011661,
-.002803,-.011226,
-.00284,-.01119,
-.01119,-.00284,
-.011631,-.002326,
-.011978,-.001744,
-.012217,-.00111,
-.012343,-.000444,
-.012352,.000233,
-.012243,.000902,
-.012019,.001541,
-.011688,.002132,
-.011259,.002656,
-.01122,.00269,
-.00733,.00659,
-.00566,.00492,
.00172,.0123,
.0123,.00172,
.00492,-.00566,
0.0*
%
%ADD30MACRO30*%
%AMMACRO22*
4,1,28,-.00052,-.00748,
-.00052,-.00984,
-.00603,-.00984,
-.006705,-.009782,
-.007359,-.009607,
-.007974,-.009321,
-.008529,-.008933,
-.009009,-.008455,
-.009398,-.0079,
-.009685,-.007286,
-.009861,-.006632,
-.00992,-.005957,
-.00992,-.00591,
-.00992,.00591,
-.009869,.006585,
-.009701,.007242,
-.009421,.007859,
-.009039,.008418,
-.008565,.008903,
-.008015,.009297,
-.007404,.009591,
-.006751,.009773,
-.006077,.00984,
-.00603,.00984,
-.00052,.00984,
-.00052,.00748,
.00991,.00748,
.00991,-.00748,
-.00052,-.00748,
0.0*
%
%ADD22MACRO22*%
%AMMACRO13*
4,1,28,.00748,-.00052,
.00984,-.00052,
.00984,-.00603,
.009782,-.006705,
.009607,-.007359,
.009321,-.007974,
.008933,-.008529,
.008455,-.009009,
.0079,-.009398,
.007286,-.009685,
.006632,-.009861,
.005957,-.00992,
.00591,-.00992,
-.00591,-.00992,
-.006585,-.009869,
-.007242,-.009701,
-.007859,-.009421,
-.008418,-.009039,
-.008903,-.008565,
-.009297,-.008015,
-.009591,-.007404,
-.009773,-.006751,
-.00984,-.006077,
-.00984,-.00603,
-.00984,-.00052,
-.00748,-.00052,
-.00748,.00991,
.00748,.00991,
.00748,-.00052,
0.0*
%
%ADD13MACRO13*%
%AMMACRO39*
4,1,8,-.0034,-.0082,
.0034,-.0082,
.0082,-.0034,
.0082,.00341,
.00341,.0082,
-.0034,.0082,
-.0082,.0034,
-.0082,-.0034,
-.0034,-.0082,
0.0*
%
%ADD39MACRO39*%
%AMMACRO38*
4,1,8,-.0082,.0034,
-.0082,-.0034,
-.0034,-.0082,
.00341,-.0082,
.0082,-.00341,
.0082,.0034,
.0034,.0082,
-.0034,.0082,
-.0082,.0034,
0.0*
%
%ADD38MACRO38*%
%AMMACRO32*
4,1,28,-.00493,-.00565,
-.0066,-.00732,
-.0027,-.01121,
-.002185,-.011649,
-.001599,-.011989,
-.000962,-.012222,
-.000295,-.01234,
.000382,-.012342,
.001049,-.012225,
.001686,-.011994,
.002273,-.011657,
.002793,-.011222,
.00283,-.01119,
.01119,-.00283,
.011629,-.002313,
.011974,-.00173,
.012212,-.001096,
.012337,-.00043,
.012344,.000247,
.012234,.000915,
.012009,.001554,
.011677,.002145,
.011247,.002668,
.01121,.0027,
.00732,.0066,
.00565,.00493,
-.00173,.0123,
-.0123,.00173,
-.00493,-.00565,
0.0*
%
%ADD32MACRO32*%
%AMMACRO29*
4,1,28,.00565,-.00493,
.00732,-.0066,
.01121,-.0027,
.011649,-.002185,
.011989,-.001599,
.012222,-.000962,
.01234,-.000295,
.012342,.000382,
.012225,.001049,
.011994,.001686,
.011657,.002273,
.011222,.002793,
.01119,.00283,
.00283,.01119,
.002313,.011629,
.00173,.011974,
.001096,.012212,
.00043,.012337,
-.000247,.012344,
-.000915,.012234,
-.001554,.012009,
-.002145,.011677,
-.002668,.011247,
-.0027,.01121,
-.0066,.00732,
-.00493,.00565,
-.0123,-.00173,
-.00173,-.0123,
.00565,-.00493,
0.0*
%
%ADD29MACRO29*%
%AMMACRO21*
4,1,28,.00051,-.00748,
.00051,-.00984,
.00602,-.00984,
.006695,-.009782,
.007349,-.009607,
.007964,-.009321,
.008519,-.008933,
.008998,-.008455,
.009388,-.0079,
.009675,-.007287,
.009851,-.006632,
.00991,-.005958,
.00991,-.00591,
.00991,.00591,
.009859,.006585,
.009691,.007242,
.009411,.007859,
.009029,.008418,
.008555,.008903,
.008005,.009297,
.007394,.00959,
.006742,.009773,
.006068,.00984,
.00602,.00984,
.00051,.00984,
.00051,.00748,
-.00992,.00748,
-.00992,-.00748,
.00051,-.00748,
0.0*
%
%ADD21MACRO21*%
%AMMACRO12*
4,1,28,.00748,.00051,
.00984,.00051,
.00984,.00602,
.009782,.006695,
.009607,.007349,
.009321,.007964,
.008933,.008519,
.008455,.008998,
.0079,.009388,
.007287,.009675,
.006632,.009851,
.005958,.00991,
.00591,.00991,
-.00591,.00991,
-.006585,.009859,
-.007242,.009691,
-.007859,.009411,
-.008418,.009029,
-.008903,.008555,
-.009297,.008005,
-.00959,.007394,
-.009773,.006742,
-.00984,.006068,
-.00984,.00602,
-.00984,.00051,
-.00748,.00051,
-.00748,-.00992,
.00748,-.00992,
.00748,.00051,
0.0*
%
%ADD12MACRO12*%
%ADD70C,.006*%
G75*
%LPD*%
G75*
G54D10*
X22047Y46417D03*
X333466D03*
G54D11*
X17116Y105500D03*
X16816Y116200D03*
X45416Y106200D03*
X47016Y376000D03*
Y384000D03*
Y388000D03*
Y380000D03*
X69016Y76500D03*
X66156Y335220D03*
X106041Y341649D03*
X106116Y337700D03*
X97016Y360000D03*
Y364000D03*
X113416Y109300D03*
X114616Y366600D03*
X114535Y362623D03*
X118116Y376800D03*
X132416Y84300D03*
X134116Y195600D03*
X124316Y234800D03*
Y238300D03*
X135716Y250700D03*
X131016Y277000D03*
X127516Y361500D03*
X149976Y141056D03*
X145766Y397500D03*
Y408000D03*
X164737Y157290D03*
X163866Y161150D03*
X163737Y181735D03*
X153536Y175720D03*
X163737Y185952D03*
Y190725D03*
X155724Y189082D03*
Y192582D03*
X157616Y228732D03*
X155241Y232300D03*
X154607Y242629D03*
X163548Y238479D03*
X166616Y228400D03*
X167450Y281848D03*
X168946Y212033D03*
X169516Y267000D03*
X182016Y422800D03*
X184897Y194343D03*
X196314Y217208D03*
X186902Y295096D03*
X185216Y300300D03*
X209272Y178269D03*
X201504Y172304D03*
X207203Y194450D03*
X207346Y203530D03*
X198747Y286781D03*
X206749Y278739D03*
X199016Y300400D03*
X219997Y172340D03*
Y176346D03*
X220293Y181892D03*
X221728Y193882D03*
X223106Y200555D03*
X222860Y210143D03*
X222726Y204555D03*
X215537Y216030D03*
X213772Y286782D03*
Y282756D03*
X222382Y275773D03*
X226409Y285912D03*
X226495Y289941D03*
X231016Y71000D03*
X242116Y71900D03*
X236516Y109760D03*
X238923Y182782D03*
X232970Y194151D03*
X239975D03*
X228611Y188938D03*
X237348Y205261D03*
X229724Y207040D03*
X233409Y283911D03*
X230369Y275841D03*
Y279853D03*
X232316Y306900D03*
X253612Y158751D03*
X253092Y203097D03*
X250343Y280778D03*
X250316Y359100D03*
Y355200D03*
X268516Y53000D03*
Y57000D03*
X268526Y117366D03*
X278318Y117391D03*
X285560Y165802D03*
X280646Y175635D03*
X278180Y209511D03*
Y213530D03*
X301598Y181885D03*
Y185885D03*
X287953Y187914D03*
X290230Y393332D03*
X312916Y122000D03*
X303516Y131290D03*
X313550Y188372D03*
X311821Y216137D03*
X308516Y373000D03*
X302766Y393352D03*
Y397382D03*
X325946Y159411D03*
X317925Y161378D03*
Y165378D03*
Y157378D03*
X325946Y179411D03*
Y183411D03*
Y187411D03*
Y191411D03*
X318946Y183411D03*
X334431Y104676D03*
Y112708D03*
Y108692D03*
X334341Y186961D03*
G54D20*
X23819Y409154D03*
X65709Y42244D03*
G54D12*
X16800Y112384D03*
X21000Y322484D03*
X48000Y97484D03*
X40400Y420284D03*
X44400D03*
X55500Y72984D03*
X59500D03*
X55500Y81984D03*
X60000Y106484D03*
X61216Y232784D03*
X64500Y71984D03*
X68500D03*
X65216Y232784D03*
X74300Y277584D03*
X66000Y287984D03*
X71900Y309984D03*
X64100Y330984D03*
X76500D03*
X78500Y402984D03*
X74500D03*
X70500D03*
X82500Y71984D03*
X90500Y74984D03*
X88700Y330984D03*
X82500Y402984D03*
X92809Y420814D03*
X88800Y420784D03*
X98500Y72484D03*
X105600Y333684D03*
X101200Y374784D03*
X103800Y384484D03*
X94500Y402984D03*
X102500D03*
X96814Y420814D03*
X115600Y121009D03*
X111600D03*
X120250Y164534D03*
X117400Y419784D03*
X132400Y91384D03*
X129500Y119484D03*
X125500Y120984D03*
X124500Y164534D03*
X127546Y231206D03*
X130000Y402484D03*
X138000Y420234D03*
X128500Y420984D03*
X139500Y143984D03*
X152450Y209278D03*
X148050Y364684D03*
X146000Y420234D03*
X150000D03*
X142000D03*
X155500Y27984D03*
X166733Y122810D03*
X156525Y153186D03*
X156467Y209278D03*
X159164Y223673D03*
X159930Y239094D03*
X160973Y252495D03*
X156963D03*
X165013D03*
X160765Y260447D03*
X156695Y260459D03*
X164801Y260445D03*
X157600Y420284D03*
X153800D03*
X179400Y17684D03*
X169500Y27484D03*
X169000Y77984D03*
X170738Y122810D03*
X178761D03*
X174741D03*
X181541Y213115D03*
X177500Y245584D03*
X173600D03*
X173992Y260315D03*
X169934Y260317D03*
X176700Y349884D03*
X181400Y365784D03*
X177500D03*
X178500Y382684D03*
X182500D03*
X194830Y83044D03*
X185470Y96434D03*
X188980Y96444D03*
X187431Y122971D03*
X191434D03*
X195500Y122984D03*
X196000Y114984D03*
X191000Y137984D03*
X195000D03*
X196332Y146900D03*
X197463Y171972D03*
X187596Y190319D03*
X193724Y189164D03*
X194567Y197581D03*
X188500Y206784D03*
X194485Y238522D03*
X198000Y264134D03*
X193800Y348384D03*
X204000Y122984D03*
X207800D03*
X199500D03*
X211370Y123004D03*
X200000Y114984D03*
X199000Y137884D03*
X207000D03*
X207486Y188953D03*
X199465Y188984D03*
X203476Y188953D03*
X206672Y212368D03*
X210333Y218539D03*
X212100Y250284D03*
X208500Y261884D03*
X201792Y274702D03*
X209811D03*
X205810D03*
X210600Y308184D03*
X227500Y96484D03*
X227370Y123010D03*
X215294D03*
X223338D03*
X219313D03*
X227061Y176337D03*
X216855Y189899D03*
X215958Y200905D03*
X213245Y241884D03*
X218800Y253544D03*
X219900Y261384D03*
X225363Y261584D03*
X223400Y268484D03*
X217120Y293778D03*
X223920Y376544D03*
X215800Y422784D03*
X233500Y96984D03*
X239590Y123010D03*
X231415D03*
X241826Y137853D03*
X231111Y176312D03*
X241200Y168384D03*
X237954Y178766D03*
X228712Y196554D03*
X239064Y212246D03*
X231021Y215721D03*
X235064D03*
X235100Y254784D03*
X239100Y253684D03*
X231250Y250434D03*
X238413Y245023D03*
X242430Y245523D03*
X242690Y260759D03*
X229265Y261907D03*
X248000Y96984D03*
X256333Y123010D03*
X243609Y123049D03*
X248087Y113123D03*
X252111D03*
X247500Y124984D03*
X252374Y137853D03*
X244500Y209484D03*
Y216484D03*
X250465Y245637D03*
X254466Y245727D03*
X246430Y245523D03*
X260346Y122510D03*
X265866Y147234D03*
X261800Y245684D03*
Y286784D03*
X265400Y420534D03*
X261400D03*
X286452Y148223D03*
X282440D03*
X282907Y186942D03*
X282240Y197743D03*
X283579Y241008D03*
X285911Y275406D03*
X281889D03*
Y285136D03*
X285911D03*
X301936Y141406D03*
X290487Y148223D03*
X301507Y192944D03*
X294162Y369036D03*
X310500Y118484D03*
X314000Y133234D03*
X310200D03*
X313936Y141406D03*
X309936D03*
X305936D03*
X305507Y192944D03*
X317116Y202434D03*
X318000Y133234D03*
X317936Y141406D03*
X321602Y190404D03*
G54D21*
X48384Y102300D03*
X58484Y86000D03*
X50014Y220480D03*
X49984Y344000D03*
Y348000D03*
Y360000D03*
X59684Y376300D03*
X59984Y367700D03*
X49984Y368000D03*
X59684Y372600D03*
X49984Y372000D03*
X73184Y287100D03*
X78784Y296700D03*
X80984Y76000D03*
X105945Y78566D03*
X115384Y249900D03*
X117484Y358500D03*
X119484Y397000D03*
X129284Y249700D03*
X130084Y283000D03*
X125484Y277000D03*
X130484Y357500D03*
Y353500D03*
X142784Y78700D03*
X148378Y152844D03*
X151184Y182110D03*
X150568Y192600D03*
X146264Y378760D03*
Y382760D03*
X148734Y392000D03*
Y401750D03*
X158384Y119200D03*
X163684Y147000D03*
X166484Y165500D03*
X167709Y153400D03*
X166484Y169500D03*
X166684Y173200D03*
X166705Y176885D03*
X158689Y181573D03*
X158692Y185582D03*
X163468Y206305D03*
X162468Y202305D03*
X156661Y326128D03*
Y330164D03*
X174274Y300900D03*
X196384Y209700D03*
Y206200D03*
X196484Y213200D03*
X192277Y217208D03*
X184861Y238444D03*
X190174Y267000D03*
X189889Y283155D03*
X186384Y279200D03*
X189889Y287221D03*
X189857Y291172D03*
X197534Y410250D03*
X211476Y172289D03*
X203277Y177969D03*
X200337Y181969D03*
X202170Y194415D03*
X203474Y203510D03*
X206305Y216270D03*
X201898Y237255D03*
X201715Y278743D03*
X209717Y286782D03*
X201715Y282773D03*
X203734Y342250D03*
Y338750D03*
X203234Y345750D03*
Y356250D03*
Y352750D03*
Y349250D03*
Y359750D03*
Y363250D03*
Y367250D03*
Y370750D03*
X217696Y193921D03*
X225518Y216136D03*
X222484Y245800D03*
X225350Y279783D03*
X219936Y372129D03*
X238097Y171773D03*
X233935Y180866D03*
X231333Y184938D03*
X229463Y293960D03*
X236884Y374100D03*
X242364Y378220D03*
X255984Y51500D03*
X250027Y194772D03*
X253311Y276756D03*
X253284Y351200D03*
Y363100D03*
X264484Y49000D03*
X271484D03*
X264484Y53000D03*
X271596Y104703D03*
Y108226D03*
X270284Y384100D03*
X277066Y121400D03*
X298484Y97600D03*
X298884Y116300D03*
X296184Y131700D03*
X295984Y126500D03*
X301335Y205854D03*
X293198Y397365D03*
X308664Y200789D03*
X314284Y260300D03*
X314984Y369000D03*
X329372Y104676D03*
Y108692D03*
Y112707D03*
X321018Y153377D03*
X328330Y150140D03*
X328914Y155411D03*
Y167411D03*
Y163411D03*
Y175411D03*
X320893Y173378D03*
Y177378D03*
X328914Y171411D03*
X320893Y169378D03*
X324745Y203664D03*
Y207664D03*
X337309Y154911D03*
Y158911D03*
Y162911D03*
Y166911D03*
X337237Y170911D03*
X337309Y182926D03*
Y178911D03*
X337237Y174911D03*
X337309Y190961D03*
X332544Y210288D03*
Y202288D03*
Y206288D03*
X333976Y386635D03*
Y390701D03*
G54D30*
X60451Y347751D03*
G54D13*
X16800Y109417D03*
X21000Y319517D03*
X48000Y94517D03*
X40400Y417317D03*
X44400D03*
X55500Y70017D03*
X59500D03*
X55500Y79017D03*
X60000Y103517D03*
X61216Y229817D03*
X64500Y69017D03*
X68500D03*
X65216Y229817D03*
X66000Y285017D03*
X74300Y274617D03*
X71900Y307017D03*
X64100Y328017D03*
X76500D03*
X78500Y400017D03*
X74500D03*
X70500D03*
X82500Y69017D03*
X90500Y72017D03*
X88700Y328017D03*
X82500Y400017D03*
X92809Y417847D03*
X88800Y417817D03*
X98500Y69517D03*
X105600Y330717D03*
X101200Y371817D03*
X103800Y381517D03*
X94500Y400017D03*
X102500D03*
X96814Y417847D03*
X115600Y118042D03*
X111600D03*
X120250Y161567D03*
X117400Y416817D03*
X132400Y88417D03*
X129500Y116517D03*
X125500Y118017D03*
X124500Y161567D03*
X127546Y228239D03*
X130000Y399517D03*
X138000Y417267D03*
X128500Y418017D03*
X139500Y141017D03*
X152450Y206311D03*
X148050Y361717D03*
X146000Y417267D03*
X150000D03*
X142000D03*
X155500Y25017D03*
X166733Y119843D03*
X156525Y150219D03*
X156467Y206311D03*
X159164Y220706D03*
X159930Y236127D03*
X160765Y257480D03*
X156695Y257492D03*
X164801Y257478D03*
X160973Y249528D03*
X156963D03*
X165013D03*
X157600Y417317D03*
X153800D03*
X179400Y14717D03*
X169500Y24517D03*
X169000Y75017D03*
X170738Y119843D03*
X178761D03*
X174741D03*
X181541Y210148D03*
X177500Y242617D03*
X173600D03*
X173992Y257348D03*
X169934Y257350D03*
X176700Y346917D03*
X181400Y362817D03*
X177500D03*
X178500Y379717D03*
X182500D03*
X185470Y93467D03*
X188980Y93477D03*
X194830Y80077D03*
X187431Y120004D03*
X191434D03*
X195500Y120017D03*
X196000Y112017D03*
X191000Y135017D03*
X195000D03*
X196332Y143933D03*
X197463Y169005D03*
X187596Y187352D03*
X193724Y186197D03*
X194567Y194614D03*
X188500Y203817D03*
X194485Y235555D03*
X198000Y261167D03*
X193800Y345417D03*
X204000Y120017D03*
X207800D03*
X199500D03*
X211370Y120037D03*
X200000Y112017D03*
X199000Y134917D03*
X207000D03*
X207486Y185986D03*
X199465Y186017D03*
X203476Y185986D03*
X206672Y209401D03*
X210333Y215572D03*
X212100Y247317D03*
X201792Y271735D03*
X208500Y258917D03*
X209811Y271735D03*
X205810D03*
X210600Y305217D03*
X227500Y93517D03*
X227370Y120043D03*
X215294D03*
X223338D03*
X219313D03*
X227061Y173370D03*
X215958Y197938D03*
X216855Y186932D03*
X213245Y238917D03*
X218800Y250577D03*
X219900Y258417D03*
X225363Y258617D03*
X223400Y265517D03*
X217120Y290811D03*
X223920Y373577D03*
X215800Y419817D03*
X233500Y94017D03*
X239590Y120043D03*
X231415D03*
X241826Y134886D03*
X241200Y165417D03*
X231111Y173345D03*
X237954Y175799D03*
X228712Y193587D03*
X231021Y212754D03*
X235064D03*
X239064Y209279D03*
X238413Y242056D03*
X242430Y242556D03*
X235100Y251817D03*
X239100Y250717D03*
X231250Y247467D03*
X242690Y257792D03*
X229265Y258940D03*
X248000Y94017D03*
X247500Y122017D03*
X256333Y120043D03*
X243609Y120082D03*
X248087Y110156D03*
X252111D03*
X252374Y134886D03*
X244500Y206517D03*
Y213517D03*
X250465Y242670D03*
X254466Y242760D03*
X246430Y242556D03*
X260346Y119543D03*
X265866Y144267D03*
X261800Y242717D03*
Y283817D03*
X265400Y417567D03*
X261400D03*
X286452Y145256D03*
X282440D03*
X282907Y183975D03*
X282240Y194776D03*
X283579Y238041D03*
X285911Y272439D03*
X281889D03*
Y282169D03*
X285911D03*
X301936Y138439D03*
X290487Y145256D03*
X301507Y189977D03*
X294162Y366069D03*
X310500Y115517D03*
X313936Y138439D03*
X309936D03*
X305936D03*
X314000Y130267D03*
X310200D03*
X305507Y189977D03*
X317116Y199467D03*
X317936Y138439D03*
X318000Y130267D03*
X321602Y187437D03*
G54D22*
X45417Y102300D03*
X47047Y220480D03*
X47017Y344000D03*
Y348000D03*
Y360000D03*
Y368000D03*
Y372000D03*
X55517Y86000D03*
X56717Y376300D03*
X57017Y367700D03*
X56717Y372600D03*
X78017Y76000D03*
X70217Y287100D03*
X75817Y296700D03*
X102978Y78566D03*
X112417Y249900D03*
X122517Y277000D03*
X114517Y358500D03*
X116517Y397000D03*
X126317Y249700D03*
X127117Y283000D03*
X127517Y357500D03*
Y353500D03*
X139817Y78700D03*
X145411Y152844D03*
X148217Y182110D03*
X147601Y192600D03*
X143297Y378760D03*
Y382760D03*
X145767Y392000D03*
Y401750D03*
X155417Y119200D03*
X160717Y147000D03*
X163517Y165500D03*
X164742Y153400D03*
X163517Y169500D03*
X163717Y173200D03*
X163738Y176885D03*
X155722Y181573D03*
X155725Y185582D03*
X160501Y206305D03*
X159501Y202305D03*
X153694Y326128D03*
Y330164D03*
X181894Y238444D03*
X171307Y300900D03*
X197370Y181969D03*
X193417Y209700D03*
Y206200D03*
X193517Y213200D03*
X189310Y217208D03*
X187207Y267000D03*
X186922Y283155D03*
X183417Y279200D03*
X186922Y287221D03*
X186890Y291172D03*
X194567Y410250D03*
X208509Y172289D03*
X200310Y177969D03*
X199203Y194415D03*
X200507Y203510D03*
X203338Y216270D03*
X198931Y237255D03*
X198748Y278743D03*
X206750Y286782D03*
X198748Y282773D03*
X200767Y342250D03*
Y338750D03*
X200267Y345750D03*
Y356250D03*
Y352750D03*
Y349250D03*
Y359750D03*
Y363250D03*
Y367250D03*
Y370750D03*
X214729Y193921D03*
X222551Y216136D03*
X219517Y245800D03*
X222383Y279783D03*
X226496Y293960D03*
X216969Y372129D03*
X235130Y171773D03*
X230968Y180866D03*
X228366Y184938D03*
X233917Y374100D03*
X239397Y378220D03*
X253017Y51500D03*
X247060Y194772D03*
X250344Y276756D03*
X250317Y351200D03*
Y363100D03*
X261517Y49000D03*
X268517D03*
X261517Y53000D03*
X268629Y104703D03*
Y108226D03*
X267317Y384100D03*
X274099Y121400D03*
X295517Y97600D03*
X295917Y116300D03*
X293217Y131700D03*
X293017Y126500D03*
X298368Y205854D03*
X290231Y397365D03*
X305697Y200789D03*
X311317Y260300D03*
X312017Y369000D03*
X326405Y104676D03*
Y108692D03*
Y112707D03*
X318051Y153377D03*
X325363Y150140D03*
X325947Y155411D03*
Y167411D03*
Y163411D03*
Y175411D03*
X317926Y173378D03*
Y177378D03*
X325947Y171411D03*
X317926Y169378D03*
X321778Y203664D03*
X329577Y210288D03*
X321778Y207664D03*
X329577Y202288D03*
Y206288D03*
X331009Y386635D03*
Y390701D03*
X334342Y154911D03*
Y158911D03*
Y162911D03*
Y166911D03*
X334270Y170911D03*
X334342Y182926D03*
Y178911D03*
X334270Y174911D03*
X334342Y190961D03*
G54D40*
X73482Y382626D03*
Y379476D03*
X89210Y360579D03*
Y357429D03*
X83900Y359275D03*
Y356125D03*
X82911Y376327D03*
Y373177D03*
X86061Y376327D03*
Y373177D03*
X89210Y376327D03*
Y373177D03*
G54D31*
X62458Y355873D03*
X58564Y354280D03*
X65607Y352724D03*
Y359023D03*
Y371584D03*
X75056Y346425D03*
X68757D03*
X81355D03*
X78206Y349574D03*
Y359023D03*
X68757Y362173D03*
X71906Y365322D03*
X87617Y352724D03*
X93916D03*
X100253Y346387D03*
X181495Y153449D03*
X175196Y156599D03*
X184645Y166047D03*
Y181795D03*
X181495Y172347D03*
X184645Y175496D03*
X178346D03*
X181495Y188095D03*
X175196Y200655D03*
X181495Y203805D03*
X175196Y206955D03*
X184645Y219553D03*
X178346Y229002D03*
X184645D03*
X197243Y159748D03*
X190944D03*
Y166047D03*
X200393Y162898D03*
X187794Y156599D03*
Y172347D03*
X194094Y222703D03*
X200393Y229002D03*
X187794Y225852D03*
X200393Y222703D03*
X209842Y159748D03*
X206692Y162898D03*
X209842Y166047D03*
X212991Y162898D03*
X203542Y159748D03*
Y225852D03*
X206692Y229002D03*
X212991D03*
X206692Y222703D03*
X225552Y166047D03*
X222402Y159748D03*
X228739Y222703D03*
X228702Y229002D03*
X225590Y225852D03*
X222440Y222703D03*
X222402Y229002D03*
X219290Y225852D03*
X231851Y166047D03*
X235001Y156599D03*
X244450Y200655D03*
X231889Y225890D03*
X250749Y169197D03*
X253898Y175496D03*
X250749Y184945D03*
X257048Y197506D03*
Y191244D03*
G54D32*
X60036Y389478D03*
G54D41*
X105316Y213343D03*
G54D50*
X115100Y402000D03*
X120900D03*
X148400Y129000D03*
X142600D03*
X148748Y220947D03*
X154548D03*
X165824Y217706D03*
X164300Y233100D03*
X171624Y217706D03*
X170100Y233100D03*
X256510Y384400D03*
X271812Y154663D03*
X270100Y170500D03*
X272100Y224500D03*
X262310Y384400D03*
X277300Y137400D03*
X283100D03*
X277612Y154663D03*
X275900Y170500D03*
X277900Y224500D03*
X281914Y218630D03*
X276114D03*
X291488Y137870D03*
X297288D03*
X327200Y120250D03*
X323611Y196486D03*
X329411D03*
X333000Y120250D03*
G54D23*
X44500Y212516D03*
X40980Y371116D03*
X48500Y417516D03*
X59500Y79016D03*
X56100Y328016D03*
X60000D03*
X52200D03*
X50000Y353016D03*
X56500Y417516D03*
X52500D03*
X60500D03*
X72500Y69016D03*
X76500D03*
X69500Y236016D03*
X66000Y274516D03*
X70000D03*
X68000Y316516D03*
X72000Y328016D03*
X68100D03*
X75000Y387016D03*
X69000D03*
X86500Y69016D03*
X80600Y254916D03*
X86500Y400016D03*
X94500Y69516D03*
X104000Y361016D03*
X98500Y400016D03*
X112500Y126016D03*
X123500Y125016D03*
X119370Y348796D03*
X135500Y141016D03*
X126000Y399516D03*
X152000Y252816D03*
Y260016D03*
X163400Y12716D03*
X162657Y119842D03*
X166717Y134885D03*
X173000Y75016D03*
X181960Y93466D03*
X170737Y134885D03*
X182954D03*
X174740D03*
X178816D03*
X177300Y216816D03*
X181300Y242516D03*
X169700Y243316D03*
X172800Y346916D03*
X178000Y338841D03*
X178500Y379716D03*
X182500D03*
X182600Y414966D03*
X187000Y135016D03*
X193343Y178502D03*
X193550Y171692D03*
X184890Y242531D03*
X192501Y250273D03*
X188500Y250266D03*
X190693Y243069D03*
X194729D03*
X197790Y271734D03*
X187070Y259426D03*
X194100Y261196D03*
X187220Y346016D03*
X210800Y134885D03*
X202900Y135016D03*
X206912Y144205D03*
X211494Y187150D03*
X198990Y242028D03*
X202990D03*
X206238Y235265D03*
X200460Y250276D03*
X204000Y261116D03*
X221500Y64516D03*
X214500Y135016D03*
X218500D03*
X222500D03*
X226500D03*
X215498Y169217D03*
X216265Y179907D03*
X222190Y185945D03*
X217200Y238716D03*
X223269Y237916D03*
X227116Y249940D03*
X214100Y255716D03*
X223100Y249316D03*
X213833Y267608D03*
X217862Y275753D03*
X213813Y275762D03*
X222293Y283801D03*
X221154Y290810D03*
X241700Y94016D03*
X235510Y120042D03*
X234500Y135216D03*
X230500Y135016D03*
X238025Y186882D03*
X238337Y198169D03*
X232713Y198176D03*
X230520Y238916D03*
X253000Y72016D03*
X244082Y108264D03*
X256100Y110116D03*
X245836Y134885D03*
X252600Y126316D03*
X256700Y134885D03*
X257500Y274016D03*
X250300Y367816D03*
X243250Y392766D03*
X260200Y134886D03*
X261863Y144338D03*
X268897Y159446D03*
X263897D03*
X271470Y216445D03*
X281000Y76016D03*
X277000D03*
X285000D03*
X276000Y162516D03*
X278868Y183974D03*
X282192Y201791D03*
X286611Y216625D03*
X283383Y245668D03*
X301936Y146388D03*
X297357Y233233D03*
X305000Y121016D03*
X313936Y146388D03*
X309936D03*
X305936D03*
X316979Y192460D03*
X317111Y208525D03*
X317936Y146388D03*
G54D14*
X18800Y122100D03*
X19000Y129500D03*
X18500Y163300D03*
X7809Y168397D03*
X21400Y178100D03*
X7809Y183397D03*
Y198397D03*
X19100Y187420D03*
X7809Y213397D03*
Y228397D03*
X18000Y234500D03*
X7809Y243397D03*
Y258397D03*
X17065Y255712D03*
X7809Y273397D03*
Y288397D03*
X8200Y302800D03*
X22000Y111400D03*
X36500Y129500D03*
X29000D03*
X24000Y138500D03*
X26000Y209500D03*
X27500Y202000D03*
X28000Y223500D03*
X26000Y216500D03*
X29900Y231400D03*
X32100Y252800D03*
X24705Y258767D03*
X22237Y304626D03*
X30638Y304602D03*
Y311957D03*
X33000Y318700D03*
X35300Y323900D03*
X29100Y327000D03*
X36200Y368400D03*
X31500Y428500D03*
X40175Y29713D03*
X40000Y104200D03*
X45000Y122500D03*
X37500Y116500D03*
X40940Y112559D03*
X51500Y114000D03*
X45000Y129500D03*
X49400Y161800D03*
X47294Y184491D03*
X48035Y191535D03*
X39408Y195990D03*
X48940Y204871D03*
X40600Y203000D03*
X39900Y211000D03*
X39567Y243133D03*
X47800Y240843D03*
X51500Y258200D03*
X37485Y258807D03*
X41100Y248900D03*
X47440Y304225D03*
X39039Y301299D03*
Y311933D03*
X50950Y318050D03*
X44481Y328760D03*
X38560Y329739D03*
X37020Y385600D03*
X46100Y412700D03*
X38000Y428800D03*
X45100Y435800D03*
X45300Y426400D03*
X59549Y63000D03*
X59945Y117795D03*
X60800Y137000D03*
X52410Y186900D03*
X59700Y196200D03*
X65380Y213120D03*
X52948Y200700D03*
X58000Y217700D03*
X55100Y225500D03*
X64500Y240400D03*
X59500Y240500D03*
X61200Y276400D03*
Y282600D03*
X55500Y315000D03*
X65400Y311900D03*
X60600Y318000D03*
X52800Y322400D03*
X59820Y341030D03*
X66070Y339780D03*
X65400Y344200D03*
X54500Y341390D03*
X54530Y348200D03*
X54500Y355000D03*
X59600Y363100D03*
X65000Y377500D03*
X54800Y381800D03*
X54600Y388000D03*
X61924Y383476D03*
X55500Y395600D03*
X58000Y412600D03*
X63715Y412385D03*
X62455Y426870D03*
X78781Y64635D03*
X74757Y83745D03*
X76580Y121904D03*
X66900Y125300D03*
X76500Y135000D03*
X70450Y138610D03*
X71124Y178565D03*
X66700Y220520D03*
X71100Y229741D03*
X74583Y217314D03*
X76200Y247400D03*
X77437Y262760D03*
X72300Y282500D03*
X77500Y316100D03*
X73301Y319575D03*
X81000Y321900D03*
X78900Y336600D03*
X71700Y340600D03*
X74500Y335700D03*
X81355Y390300D03*
X79000Y395500D03*
X73976Y408665D03*
X69139Y413452D03*
X74782Y413800D03*
X73971Y429200D03*
X91358Y83745D03*
X88500Y128000D03*
X81500Y176515D03*
X87500Y237300D03*
X92300Y282100D03*
X94812Y301312D03*
X93000Y315000D03*
X88700Y318300D03*
X92698Y323224D03*
X84800Y344100D03*
X92900Y342800D03*
X88700Y337123D03*
X83900Y385700D03*
X94200Y391000D03*
X96030Y409400D03*
X84320Y430510D03*
X94710Y433260D03*
X89500Y432000D03*
X84000Y425500D03*
X105722Y59722D03*
X111000Y77000D03*
X104500Y73500D03*
X110950Y82050D03*
X111075Y104600D03*
X98720Y236980D03*
X103580Y237400D03*
X106600Y253689D03*
X106574Y280028D03*
X99990Y307900D03*
X100500Y328547D03*
X98377Y341523D03*
X105900Y376900D03*
X98500Y394800D03*
X108701Y418300D03*
X108336Y411547D03*
X109048Y425853D03*
X106550Y431630D03*
X103461Y425875D03*
X125800Y47330D03*
X112800Y60400D03*
X112600Y52800D03*
X125800Y69000D03*
X113000Y88500D03*
X123325Y111000D03*
X120500Y115525D03*
X120300Y134800D03*
X118990Y128536D03*
X113590Y245170D03*
X112900Y239200D03*
X124559Y255500D03*
X115475Y254900D03*
X111600Y262730D03*
X113157Y270929D03*
X111600Y284000D03*
X122957Y300991D03*
X123100Y295974D03*
X124935Y324900D03*
X124300Y348800D03*
X114060Y340640D03*
X119370Y344050D03*
X122200Y356400D03*
X111950Y371200D03*
X122047Y372260D03*
X125650Y368650D03*
X122330Y364670D03*
X119200Y389700D03*
X117410Y381350D03*
X112800Y421600D03*
X116632Y411500D03*
X122498Y419675D03*
X112796Y412490D03*
X117900Y425980D03*
X140730Y72600D03*
X133000Y78900D03*
X126800Y132900D03*
X140500Y134500D03*
X132500Y167300D03*
X128900Y183700D03*
X135300Y175100D03*
X133433Y186400D03*
X138900Y219500D03*
X127200Y223700D03*
X134891Y225171D03*
X138608Y235001D03*
X133608D03*
X138000Y244600D03*
X137059Y255568D03*
X134788Y283000D03*
X136100Y334000D03*
X140950Y390050D03*
X127950Y395750D03*
X134400Y394600D03*
X129135Y410250D03*
X128866Y433066D03*
X135350Y433016D03*
X128500Y426070D03*
X140820Y433030D03*
X134805Y427395D03*
X143000Y17310D03*
X146200Y28075D03*
X151000Y24925D03*
X152801Y70349D03*
X152800Y75600D03*
X145100Y87400D03*
X147587Y119813D03*
X149800Y135100D03*
X144800Y141700D03*
X148429Y147682D03*
X144500Y169570D03*
X146882Y177501D03*
X148967Y173433D03*
X141694Y196204D03*
X145100Y208800D03*
X143742Y203395D03*
X152400Y226300D03*
X142702Y227817D03*
X149862Y243788D03*
X150430Y231000D03*
X145250Y256890D03*
X152300Y248200D03*
X147150Y273000D03*
X141890Y310570D03*
X153500Y373400D03*
X145703Y370700D03*
X150210Y369250D03*
X148490Y374259D03*
X153330Y391710D03*
X152500Y382600D03*
X150820Y387325D03*
X154110Y404090D03*
X154638Y396566D03*
X146000Y429900D03*
X141185Y426899D03*
X158732Y12625D03*
X158952Y20203D03*
X169500Y32000D03*
X165000Y24500D03*
X156710Y73420D03*
X168985Y71000D03*
X156286Y124903D03*
X166733Y128700D03*
X159328Y160847D03*
X164000Y197700D03*
X169000Y199000D03*
X157500Y214700D03*
X170600Y204300D03*
X170000Y223500D03*
X169520Y252810D03*
X160300Y281848D03*
X161635Y276500D03*
X160850Y301344D03*
X170800Y317600D03*
X159510Y312500D03*
X161154Y376704D03*
X156300Y376300D03*
X165501Y382800D03*
X158200Y381400D03*
X162100Y414000D03*
X156101Y425100D03*
X165500Y433100D03*
X184500Y15500D03*
X182108Y129094D03*
X174553Y128728D03*
X175400Y149000D03*
X175450Y143704D03*
X181752Y147052D03*
X171507Y162892D03*
X171600Y178000D03*
X171677Y172607D03*
X171443Y183557D03*
X176800Y194200D03*
X176144Y232863D03*
X179754Y250150D03*
X180458Y258825D03*
X174400Y251936D03*
X181863Y289871D03*
X175013Y281583D03*
X178900Y301100D03*
X172800Y354646D03*
X178682Y430173D03*
X184480Y429370D03*
X174830Y427848D03*
X172060Y433100D03*
X190500Y18000D03*
X193100Y69100D03*
X194600Y89900D03*
X194500Y106200D03*
X186891Y113991D03*
X187435Y129623D03*
X195983Y129294D03*
X187172Y143672D03*
X200400Y151600D03*
X193267Y278328D03*
X200396Y291531D03*
X194294Y300400D03*
X187180Y329590D03*
X187570Y337590D03*
X194200Y351930D03*
X189500Y368900D03*
X187400Y379400D03*
X187300Y384300D03*
X197660Y390870D03*
X195800Y396780D03*
X190370Y422490D03*
X199940Y423700D03*
X197600Y415400D03*
X194600Y419660D03*
X192470Y414850D03*
X188239Y417654D03*
X195300Y432327D03*
X204100Y67400D03*
X204504Y113507D03*
X211490Y143700D03*
X202247Y145400D03*
X211300Y151100D03*
X207610Y242910D03*
X210770Y313524D03*
X210930Y318643D03*
X202440Y333420D03*
X208320Y348291D03*
X208300Y338200D03*
X208315Y343235D03*
X208340Y353360D03*
X208350Y358370D03*
X208120Y363410D03*
X202240Y378980D03*
X208350Y369750D03*
X210550Y375290D03*
X208360Y384890D03*
X208565Y404501D03*
X205223Y422665D03*
X206150Y412821D03*
X223800Y50700D03*
X224000Y74275D03*
X226000Y68000D03*
X216400Y106400D03*
X226040Y101220D03*
X222100Y112100D03*
X229342Y129240D03*
X221278Y129294D03*
X228766Y142545D03*
X218631Y151131D03*
X221400Y142600D03*
X223007Y153967D03*
X217000Y233800D03*
X227820Y233900D03*
X230196Y267477D03*
X218400Y270400D03*
X226783Y298849D03*
X216384Y312216D03*
X228800Y312100D03*
X218500Y318800D03*
X219220Y307580D03*
X216250Y328130D03*
X228680Y376635D03*
X222575Y387625D03*
X227206Y400100D03*
X220134Y400780D03*
X240000Y67400D03*
X235630Y104990D03*
X231592Y110500D03*
X235880Y115000D03*
X242500Y129000D03*
X236623Y128797D03*
X239118Y145170D03*
X239624Y154064D03*
X232384Y148884D03*
X244850Y153350D03*
X238385Y232466D03*
X235070Y236989D03*
X239298Y268800D03*
X241277Y274649D03*
X234946Y271298D03*
X235108Y262780D03*
X241263Y282654D03*
X239693Y288930D03*
X234693D03*
X238900Y296950D03*
X245300Y361100D03*
X234815Y379895D03*
X243250Y385930D03*
X256000Y56000D03*
X259106Y66000D03*
X252900Y80400D03*
X254900Y92500D03*
X256500Y98500D03*
X257422Y129840D03*
X258500Y146400D03*
X247546Y142562D03*
X252586Y142376D03*
X248988Y157001D03*
X258500Y169000D03*
X259200Y163600D03*
X260000Y210900D03*
X259800Y222600D03*
X247700Y229400D03*
X259000Y237600D03*
X259500Y258800D03*
X250900Y250800D03*
X253100Y257800D03*
X258100Y295080D03*
X245900Y305000D03*
X246000Y333900D03*
X257046Y331377D03*
X254340Y346320D03*
X256320Y341490D03*
X256124Y336355D03*
X245400Y355800D03*
X245430Y367305D03*
X257095Y428796D03*
X267939Y41122D03*
X272505Y83545D03*
X267060Y124750D03*
X268256Y112794D03*
X272100Y137400D03*
X260733Y154500D03*
X267909Y185096D03*
X271209Y177524D03*
X264200Y172300D03*
X266346Y219380D03*
X264100Y235500D03*
X266647Y252636D03*
X261800Y250300D03*
X260500Y300500D03*
X262310Y311225D03*
X261300Y334100D03*
X274190Y408900D03*
X269700Y411379D03*
X271500Y418300D03*
X267100Y432900D03*
X263800Y430300D03*
X272999Y430500D03*
X262190Y425300D03*
X286000Y47000D03*
X290000Y82000D03*
X277505Y83545D03*
X282505D03*
X278394Y111035D03*
X278220Y101530D03*
X288116Y120306D03*
X280400Y126000D03*
X287796Y131542D03*
X288280Y126212D03*
X286000Y157000D03*
X287908Y170320D03*
X289254Y194839D03*
X286106Y210587D03*
X289000Y244900D03*
X288192Y237704D03*
X289701Y255679D03*
X278029Y249108D03*
X284357Y267027D03*
X287507Y301596D03*
X289939Y309060D03*
X289600Y322253D03*
X286372Y326768D03*
X283973Y382553D03*
X285472Y394583D03*
X278900Y421400D03*
X281300Y416200D03*
X277700Y412580D03*
X280765Y431556D03*
X297466Y51521D03*
X297575Y73738D03*
X290840Y96350D03*
X304000Y116500D03*
X291360Y116390D03*
X300500Y125000D03*
X296075Y122000D03*
X292200Y154900D03*
X300819Y154564D03*
X292572Y160025D03*
X295410Y172936D03*
X298714Y210477D03*
X292404Y201282D03*
X299667Y201334D03*
X292404Y213737D03*
X290700Y221600D03*
X303688Y237034D03*
X303918Y243252D03*
X299100Y286500D03*
X291000Y297700D03*
X298705Y369127D03*
X298152Y393332D03*
X292700Y403700D03*
X317000Y111500D03*
X315100Y116400D03*
X309394Y153989D03*
X311269Y159165D03*
X310598Y174488D03*
X305002Y172936D03*
X310866Y179672D03*
X311158Y194839D03*
Y210587D03*
X309521Y226397D03*
X305700Y216300D03*
X309521Y235352D03*
X319700Y248600D03*
X316276Y255376D03*
X312114Y288439D03*
X312272Y282107D03*
X307668Y285160D03*
X306200Y308800D03*
X307000Y367500D03*
X310431Y393352D03*
X308926Y401900D03*
X321800Y109000D03*
X320938Y122677D03*
X322530Y138950D03*
X331641Y141743D03*
X328798Y216364D03*
X323798D03*
X322700Y288600D03*
X330200D03*
X322700Y296100D03*
Y303600D03*
X330200D03*
Y296100D03*
X325900Y365643D03*
X326100Y375717D03*
X326200Y370681D03*
X326375Y380724D03*
X333300Y403400D03*
X321100Y410400D03*
X339101Y117328D03*
X337842Y128533D03*
X335400Y133400D03*
X343600Y133900D03*
X337700Y144300D03*
Y227900D03*
X347500Y350000D03*
X335475Y367500D03*
X347500Y388000D03*
X335500Y380000D03*
G54D33*
X57937Y391577D03*
G54D51*
X143118Y44803D03*
X194851D03*
G54D42*
X90761Y368528D03*
X87611D03*
X92360Y382626D03*
X100539Y378300D03*
X97389D03*
X95510Y382626D03*
G54D24*
X44500Y215483D03*
X40980Y374083D03*
X48500Y420483D03*
X59500Y81983D03*
X56100Y330983D03*
X60000D03*
X52200D03*
X50000Y355983D03*
X56500Y420483D03*
X52500D03*
X60500D03*
X72500Y71983D03*
X76500D03*
X69500Y238983D03*
X66000Y277483D03*
X70000D03*
X68000Y319483D03*
X72000Y330983D03*
X68100D03*
X75000Y389983D03*
X69000D03*
X86500Y71983D03*
X80600Y257883D03*
X86500Y402983D03*
X94500Y72483D03*
X104000Y363983D03*
X98500Y402983D03*
X112500Y128983D03*
X123500Y127983D03*
X119370Y351763D03*
X135500Y143983D03*
X126000Y402483D03*
X152000Y255783D03*
Y262983D03*
X163400Y15683D03*
X162657Y122809D03*
X166717Y137852D03*
X173000Y77983D03*
X181960Y96433D03*
X170737Y137852D03*
X182954D03*
X174740D03*
X178816D03*
X177300Y219783D03*
X169700Y246283D03*
X181300Y245483D03*
X178000Y341808D03*
X172800Y349883D03*
X178500Y382683D03*
X182500D03*
X182600Y417933D03*
X187000Y137983D03*
X193343Y181469D03*
X193550Y174659D03*
X192501Y253240D03*
X188500Y253233D03*
X190693Y246036D03*
X194729D03*
X184890Y245498D03*
X187070Y262393D03*
X194100Y264163D03*
X197790Y274701D03*
X187220Y348983D03*
X210800Y137852D03*
X202900Y137983D03*
X206912Y147172D03*
X211494Y190117D03*
X206238Y238232D03*
X200460Y253243D03*
X198990Y244995D03*
X202990D03*
X204000Y264083D03*
X221500Y67483D03*
X214500Y137983D03*
X218500D03*
X222500D03*
X226500D03*
X215498Y172184D03*
X216265Y182874D03*
X222190Y188912D03*
X217200Y241683D03*
X223269Y240883D03*
X227116Y252907D03*
X223100Y252283D03*
X213833Y270575D03*
X214100Y258683D03*
X217862Y278720D03*
X213813Y278729D03*
X222293Y286768D03*
X221154Y293777D03*
X241700Y96983D03*
X235510Y123009D03*
X234500Y138183D03*
X230500Y137983D03*
X238025Y189849D03*
X238337Y201136D03*
X232713Y201143D03*
X230520Y241883D03*
X253000Y74983D03*
X256100Y113083D03*
X244082Y111231D03*
X245836Y137852D03*
X252600Y129283D03*
X256700Y137852D03*
X257500Y276983D03*
X250300Y370783D03*
X243250Y395733D03*
X260200Y137853D03*
X261863Y147305D03*
X268897Y162413D03*
X263897D03*
X271470Y219412D03*
X281000Y78983D03*
X277000D03*
X285000D03*
X276000Y165483D03*
X278868Y186941D03*
X282192Y204758D03*
X286611Y219592D03*
X283383Y248635D03*
X301936Y149355D03*
X297357Y236200D03*
X305000Y123983D03*
X313936Y149355D03*
X309936D03*
X305936D03*
X316979Y195427D03*
X317111Y211492D03*
X317936Y149355D03*
G54D15*
X30859Y14328D03*
X31500Y443500D03*
X137400Y323800D03*
X205900Y99500D03*
X270100Y198000D03*
X297000Y270500D03*
G54D60*
X163110Y364169D03*
G54D70*
G01X2010999Y-388000D02*
Y1475775D01*
X-407000D01*
Y-386798D01*
Y-755294D01*
Y-793716D01*
X-368578D01*
X1942346D01*
X2010999D01*
Y-725063D01*
Y-388000D01*
G01X-53307Y-609436D02*
Y-684436D01*
X446693D01*
Y-609436D01*
X-53307D01*
G01X-41307Y-674436D02*
Y-679436D01*
G01X-42764Y-674436D02*
X-39850D01*
G01X-34940Y-679436D02*
X-37474D01*
Y-674436D01*
X-34940D01*
G01X-35954Y-676853D02*
X-37474D01*
G01X-32374Y-674436D02*
Y-679436D01*
X-29840D01*
G01X-26007Y-679603D02*
X-26134Y-679519D01*
Y-679353D01*
X-26007Y-679269D01*
X-25880Y-679353D01*
Y-679519D01*
X-26007Y-679603D01*
G01Y-677353D02*
X-26134Y-677269D01*
Y-677103D01*
X-26007Y-677019D01*
X-25880Y-677103D01*
Y-677269D01*
X-26007Y-677353D01*
G01X-21224Y-681103D02*
X-21857Y-680269D01*
X-22174Y-679436D01*
Y-676103D01*
X-21857Y-675269D01*
X-21224Y-674436D01*
G01X-15807D02*
X-16314Y-674603D01*
X-16694Y-675019D01*
X-16947Y-675519D01*
X-17137Y-676186D01*
X-17200Y-676936D01*
X-17137Y-677686D01*
X-16947Y-678353D01*
X-16694Y-678853D01*
X-16314Y-679269D01*
X-15807Y-679436D01*
X-15300Y-679269D01*
X-14920Y-678853D01*
X-14667Y-678353D01*
X-14477Y-677686D01*
X-14414Y-676936D01*
X-14477Y-676186D01*
X-14667Y-675519D01*
X-14920Y-675019D01*
X-15300Y-674603D01*
X-15807Y-674436D01*
G01X-12100Y-678436D02*
X-11720Y-679019D01*
X-11214Y-679353D01*
X-10644Y-679436D01*
X-10137Y-679353D01*
X-9630Y-678936D01*
X-9314Y-678436D01*
X-9250Y-677936D01*
X-9377Y-677353D01*
X-9820Y-676936D01*
X-10264Y-676769D01*
X-10834D01*
G01X-10264D02*
X-9884Y-676519D01*
X-9567Y-676103D01*
X-9440Y-675603D01*
X-9567Y-675103D01*
X-9884Y-674686D01*
X-10454Y-674436D01*
X-11024Y-674519D01*
X-11594Y-674853D01*
G01X-5290Y-681103D02*
X-4657Y-680269D01*
X-4340Y-679436D01*
Y-676103D01*
X-4657Y-675269D01*
X-5290Y-674436D01*
G01X-1900Y-678436D02*
X-1520Y-679019D01*
X-1014Y-679353D01*
X-444Y-679436D01*
X63Y-679353D01*
X570Y-678936D01*
X886Y-678436D01*
X950Y-677936D01*
X823Y-677353D01*
X380Y-676936D01*
X-64Y-676769D01*
X-634D01*
G01X-64D02*
X316Y-676519D01*
X633Y-676103D01*
X760Y-675603D01*
X633Y-675103D01*
X316Y-674686D01*
X-254Y-674436D01*
X-824Y-674519D01*
X-1394Y-674853D01*
G01X3390Y-675269D02*
X3770Y-674769D01*
X4213Y-674519D01*
X4720Y-674436D01*
X5353Y-674603D01*
X5796Y-675019D01*
X5923Y-675519D01*
X5860Y-676019D01*
X5606Y-676436D01*
X4340Y-677269D01*
X3770Y-677853D01*
X3390Y-678686D01*
X3263Y-679436D01*
X5923D01*
G01X9566D02*
X9693Y-678353D01*
X9883Y-677436D01*
X10136Y-676603D01*
X10453Y-675686D01*
X10960Y-674436D01*
X8426D01*
G01X13970Y-677769D02*
X15616D01*
G01X18690Y-675269D02*
X19070Y-674769D01*
X19513Y-674519D01*
X20020Y-674436D01*
X20653Y-674603D01*
X21096Y-675019D01*
X21223Y-675519D01*
X21160Y-676019D01*
X20906Y-676436D01*
X19640Y-677269D01*
X19070Y-677853D01*
X18690Y-678686D01*
X18563Y-679436D01*
X21223D01*
G01X23600Y-678436D02*
X23980Y-679019D01*
X24486Y-679353D01*
X25056Y-679436D01*
X25563Y-679353D01*
X26070Y-678936D01*
X26386Y-678436D01*
X26450Y-677936D01*
X26323Y-677353D01*
X25880Y-676936D01*
X25436Y-676769D01*
X24866D01*
G01X25436D02*
X25816Y-676519D01*
X26133Y-676103D01*
X26260Y-675603D01*
X26133Y-675103D01*
X25816Y-674686D01*
X25246Y-674436D01*
X24676Y-674519D01*
X24106Y-674853D01*
G01X30853Y-679436D02*
Y-674436D01*
X28510Y-678019D01*
X31676D01*
G01X33800Y-678686D02*
X34180Y-679103D01*
X34623Y-679353D01*
X35193Y-679436D01*
X35763Y-679269D01*
X36206Y-678936D01*
X36523Y-678353D01*
X36586Y-677686D01*
X36460Y-677019D01*
X36143Y-676603D01*
X35700Y-676269D01*
X35256Y-676186D01*
X34813Y-676269D01*
X34243Y-676603D01*
X34433Y-674436D01*
X36143D01*
G01X44190Y-679436D02*
Y-674436D01*
X46596D01*
G01X45710Y-676853D02*
X44190D01*
G01X48910Y-679436D02*
X50493Y-674436D01*
X52076Y-679436D01*
G01X51506Y-677686D02*
X49480D01*
G01X54263Y-679436D02*
X56923Y-674436D01*
G01X54263D02*
X56923Y-679436D01*
G01X60693Y-679603D02*
X60566Y-679519D01*
Y-679353D01*
X60693Y-679269D01*
X60820Y-679353D01*
Y-679519D01*
X60693Y-679603D01*
G01Y-677353D02*
X60566Y-677269D01*
Y-677103D01*
X60693Y-677019D01*
X60820Y-677103D01*
Y-677269D01*
X60693Y-677353D01*
G01X65476Y-681103D02*
X64843Y-680269D01*
X64526Y-679436D01*
Y-676103D01*
X64843Y-675269D01*
X65476Y-674436D01*
G01X70893D02*
X70386Y-674603D01*
X70006Y-675019D01*
X69753Y-675519D01*
X69563Y-676186D01*
X69500Y-676936D01*
X69563Y-677686D01*
X69753Y-678353D01*
X70006Y-678853D01*
X70386Y-679269D01*
X70893Y-679436D01*
X71400Y-679269D01*
X71780Y-678853D01*
X72033Y-678353D01*
X72223Y-677686D01*
X72286Y-676936D01*
X72223Y-676186D01*
X72033Y-675519D01*
X71780Y-675019D01*
X71400Y-674603D01*
X70893Y-674436D01*
G01X74600Y-678436D02*
X74980Y-679019D01*
X75486Y-679353D01*
X76056Y-679436D01*
X76563Y-679353D01*
X77070Y-678936D01*
X77386Y-678436D01*
X77450Y-677936D01*
X77323Y-677353D01*
X76880Y-676936D01*
X76436Y-676769D01*
X75866D01*
G01X76436D02*
X76816Y-676519D01*
X77133Y-676103D01*
X77260Y-675603D01*
X77133Y-675103D01*
X76816Y-674686D01*
X76246Y-674436D01*
X75676Y-674519D01*
X75106Y-674853D01*
G01X81410Y-681103D02*
X82043Y-680269D01*
X82360Y-679436D01*
Y-676103D01*
X82043Y-675269D01*
X81410Y-674436D01*
G01X84800Y-678436D02*
X85180Y-679019D01*
X85686Y-679353D01*
X86256Y-679436D01*
X86763Y-679353D01*
X87270Y-678936D01*
X87586Y-678436D01*
X87650Y-677936D01*
X87523Y-677353D01*
X87080Y-676936D01*
X86636Y-676769D01*
X86066D01*
G01X86636D02*
X87016Y-676519D01*
X87333Y-676103D01*
X87460Y-675603D01*
X87333Y-675103D01*
X87016Y-674686D01*
X86446Y-674436D01*
X85876Y-674519D01*
X85306Y-674853D01*
G01X90216Y-678853D02*
X90660Y-679269D01*
X91166Y-679436D01*
X91673Y-679269D01*
X92116Y-678769D01*
X92433Y-678019D01*
X92560Y-677269D01*
Y-676353D01*
X92433Y-675603D01*
X92116Y-674936D01*
X91736Y-674603D01*
X91293Y-674436D01*
X90786Y-674603D01*
X90406Y-674936D01*
X90153Y-675436D01*
X90026Y-676103D01*
X90153Y-676686D01*
X90470Y-677269D01*
X90850Y-677603D01*
X91293Y-677686D01*
X91800Y-677519D01*
X92180Y-677103D01*
X92560Y-676353D01*
G01X96266Y-679436D02*
X96393Y-678353D01*
X96583Y-677436D01*
X96836Y-676603D01*
X97153Y-675686D01*
X97660Y-674436D01*
X95126D01*
G01X100670Y-677769D02*
X102316D01*
G01X105200Y-678436D02*
X105580Y-679019D01*
X106086Y-679353D01*
X106656Y-679436D01*
X107163Y-679353D01*
X107670Y-678936D01*
X107986Y-678436D01*
X108050Y-677936D01*
X107923Y-677353D01*
X107480Y-676936D01*
X107036Y-676769D01*
X106466D01*
G01X107036D02*
X107416Y-676519D01*
X107733Y-676103D01*
X107860Y-675603D01*
X107733Y-675103D01*
X107416Y-674686D01*
X106846Y-674436D01*
X106276Y-674519D01*
X105706Y-674853D01*
G01X110490Y-677353D02*
X110933Y-676769D01*
X111313Y-676436D01*
X111820Y-676269D01*
X112263Y-676436D01*
X112580Y-676769D01*
X112833Y-677269D01*
X112896Y-677853D01*
X112833Y-678353D01*
X112580Y-678853D01*
X112200Y-679269D01*
X111756Y-679436D01*
X111250Y-679269D01*
X110806Y-678769D01*
X110553Y-678019D01*
X110490Y-677186D01*
X110616Y-676103D01*
X110806Y-675519D01*
X111123Y-674936D01*
X111566Y-674519D01*
X112010Y-674436D01*
X112453Y-674603D01*
X112770Y-675019D01*
G01X116793Y-679436D02*
Y-674436D01*
X116033Y-675436D01*
G01Y-679436D02*
X117553D01*
G01X122653D02*
Y-674436D01*
X120310Y-678019D01*
X123476D01*
G01X141693Y-609436D02*
Y-684436D01*
G01Y-659436D02*
X244693D01*
Y-634436D01*
G01X141693D02*
X244693D01*
G01X246693Y-609436D02*
Y-684436D01*
G01X244693Y-609436D02*
Y-684436D01*
G01X252200Y-669436D02*
Y-664436D01*
X253466D01*
X253973Y-664686D01*
X254353Y-665019D01*
X254670Y-665519D01*
X254923Y-666103D01*
X254986Y-666936D01*
X254923Y-667769D01*
X254670Y-668353D01*
X254353Y-668853D01*
X253973Y-669186D01*
X253466Y-669436D01*
X252200D01*
G01X257110D02*
X258693Y-664436D01*
X260276Y-669436D01*
G01X259706Y-667686D02*
X257680D01*
G01X263793Y-664436D02*
Y-669436D01*
G01X262336Y-664436D02*
X265250D01*
G01X270160Y-669436D02*
X267626D01*
Y-664436D01*
X270160D01*
G01X269146Y-666853D02*
X267626D01*
G01X273993Y-669603D02*
X273866Y-669519D01*
Y-669353D01*
X273993Y-669269D01*
X274120Y-669353D01*
Y-669519D01*
X273993Y-669603D01*
G01Y-667353D02*
X273866Y-667269D01*
Y-667103D01*
X273993Y-667019D01*
X274120Y-667103D01*
Y-667269D01*
X273993Y-667353D01*
G01X246693Y-659436D02*
X446693D01*
G01X252326Y-644436D02*
Y-639436D01*
X253846D01*
X254353Y-639686D01*
X254733Y-640269D01*
X254860Y-640936D01*
X254733Y-641603D01*
X254416Y-642103D01*
X253846Y-642353D01*
X252326D01*
G01X257553Y-644603D02*
X259833Y-639436D01*
G01X262336Y-644436D02*
Y-639436D01*
X265250Y-644436D01*
Y-639436D01*
G01X268893Y-644603D02*
X268766Y-644519D01*
Y-644353D01*
X268893Y-644269D01*
X269020Y-644353D01*
Y-644519D01*
X268893Y-644603D01*
G01Y-642353D02*
X268766Y-642269D01*
Y-642103D01*
X268893Y-642019D01*
X269020Y-642103D01*
Y-642269D01*
X268893Y-642353D01*
G01X246693Y-634436D02*
X446693D01*
G01X252326Y-619436D02*
Y-614436D01*
X253846D01*
X254353Y-614686D01*
X254733Y-615269D01*
X254860Y-615936D01*
X254733Y-616603D01*
X254416Y-617103D01*
X253846Y-617353D01*
X252326D01*
G01X257426Y-619436D02*
Y-614436D01*
X259010D01*
X259516Y-614686D01*
X259833Y-615019D01*
X259960Y-615686D01*
X259833Y-616353D01*
X259453Y-616769D01*
X259010Y-617019D01*
X257426D01*
G01X259010D02*
X259960Y-619436D01*
G01X263793D02*
X263286Y-619353D01*
X262843Y-619019D01*
X262463Y-618519D01*
X262210Y-617936D01*
X262083Y-617269D01*
Y-616603D01*
X262210Y-615936D01*
X262463Y-615353D01*
X262843Y-614853D01*
X263286Y-614519D01*
X263793Y-614436D01*
X264300Y-614519D01*
X264743Y-614853D01*
X265123Y-615353D01*
X265376Y-615936D01*
X265503Y-616603D01*
Y-617269D01*
X265376Y-617936D01*
X265123Y-618519D01*
X264743Y-619019D01*
X264300Y-619353D01*
X263793Y-619436D01*
G01X267626Y-618436D02*
X267943Y-618936D01*
X268323Y-619269D01*
X268766Y-619436D01*
X269273Y-619269D01*
X269653Y-618936D01*
X270033Y-618436D01*
X270160Y-617769D01*
Y-614436D01*
G01X275260Y-619436D02*
X272726D01*
Y-614436D01*
X275260D01*
G01X274246Y-616853D02*
X272726D01*
G01X280486Y-614853D02*
X280106Y-614603D01*
X279663Y-614436D01*
X279156D01*
X278586Y-614686D01*
X278143Y-615103D01*
X277826Y-615603D01*
X277573Y-616436D01*
X277510Y-617186D01*
X277636Y-617936D01*
X277826Y-618436D01*
X278206Y-618936D01*
X278650Y-619269D01*
X279093Y-619436D01*
X279536D01*
X279980Y-619269D01*
X280360Y-619019D01*
X280676Y-618686D01*
G01X284193Y-614436D02*
Y-619436D01*
G01X282736Y-614436D02*
X285650D01*
G01X289293Y-619603D02*
X289166Y-619519D01*
Y-619353D01*
X289293Y-619269D01*
X289420Y-619353D01*
Y-619519D01*
X289293Y-619603D01*
G01Y-617353D02*
X289166Y-617269D01*
Y-617103D01*
X289293Y-617019D01*
X289420Y-617103D01*
Y-617269D01*
X289293Y-617353D01*
G01X361693Y-659436D02*
Y-684436D01*
G01X364326Y-661936D02*
Y-666936D01*
X366860D01*
G01X369933Y-661936D02*
X371453D01*
G01X370693D02*
Y-666936D01*
G01X369933D02*
X371453D01*
G01X376300Y-664269D02*
X376553Y-664019D01*
X376743Y-663603D01*
X376870Y-663019D01*
X376743Y-662519D01*
X376490Y-662186D01*
X376046Y-661936D01*
X374336D01*
Y-666936D01*
X376426D01*
X376870Y-666603D01*
X377123Y-666103D01*
X377250Y-665519D01*
X377123Y-664936D01*
X376743Y-664436D01*
X376300Y-664269D01*
X374336D01*
G01X380893Y-667103D02*
X380766Y-667019D01*
Y-666853D01*
X380893Y-666769D01*
X381020Y-666853D01*
Y-667019D01*
X380893Y-667103D01*
G01Y-664853D02*
X380766Y-664769D01*
Y-664603D01*
X380893Y-664519D01*
X381020Y-664603D01*
Y-664769D01*
X380893Y-664853D01*
G01X404693Y-659436D02*
Y-684436D01*
G01Y-634436D02*
Y-659436D01*
G01X412706Y-687603D02*
X412813Y-687478D01*
X412893Y-687269D01*
X412946Y-686978D01*
X412893Y-686728D01*
X412786Y-686561D01*
X412600Y-686436D01*
X411880D01*
Y-688936D01*
X412760D01*
X412946Y-688769D01*
X413053Y-688519D01*
X413106Y-688228D01*
X413053Y-687936D01*
X412893Y-687686D01*
X412706Y-687603D01*
X411880D01*
G01X415173Y-688936D02*
Y-687269D01*
G01Y-687561D02*
X415066Y-687394D01*
X414906Y-687311D01*
X414720Y-687269D01*
X414533Y-687353D01*
X414373Y-687519D01*
X414266Y-687769D01*
X414213Y-688103D01*
X414266Y-688436D01*
X414373Y-688686D01*
X414533Y-688853D01*
X414720Y-688936D01*
X414906Y-688894D01*
X415066Y-688769D01*
X415173Y-688603D01*
G01X416493Y-688644D02*
X416626Y-688811D01*
X416813Y-688936D01*
X416973D01*
X417133Y-688853D01*
X417240Y-688728D01*
X417293Y-688561D01*
X417266Y-688311D01*
X417160Y-688186D01*
X416680Y-687936D01*
X416573Y-687644D01*
X416626Y-687436D01*
X416733Y-687311D01*
X416893Y-687269D01*
X417053Y-687311D01*
X417213Y-687436D01*
G01X418693Y-687811D02*
X419546D01*
X419466Y-687519D01*
X419333Y-687353D01*
X419146Y-687269D01*
X418960Y-687311D01*
X418800Y-687436D01*
X418693Y-687728D01*
X418640Y-687978D01*
Y-688228D01*
X418693Y-688478D01*
X418826Y-688728D01*
X418986Y-688894D01*
X419173Y-688936D01*
X419360Y-688853D01*
X419546Y-688603D01*
G01X420813Y-688936D02*
Y-686436D01*
G01Y-687686D02*
X420946Y-687436D01*
X421106Y-687311D01*
X421266Y-687269D01*
X421506Y-687353D01*
X421666Y-687519D01*
X421773Y-687811D01*
Y-688144D01*
X421720Y-688478D01*
X421613Y-688728D01*
X421426Y-688894D01*
X421266Y-688936D01*
X421106Y-688894D01*
X420946Y-688769D01*
X420813Y-688561D01*
G01X423493Y-688936D02*
X423333Y-688894D01*
X423173Y-688728D01*
X423066Y-688436D01*
X423013Y-688103D01*
X423066Y-687769D01*
X423173Y-687478D01*
X423333Y-687311D01*
X423493Y-687269D01*
X423653Y-687311D01*
X423813Y-687478D01*
X423920Y-687769D01*
X423946Y-688103D01*
X423920Y-688436D01*
X423813Y-688728D01*
X423653Y-688894D01*
X423493Y-688936D01*
G01X426173D02*
Y-687269D01*
G01Y-687561D02*
X426066Y-687394D01*
X425906Y-687311D01*
X425720Y-687269D01*
X425533Y-687353D01*
X425373Y-687519D01*
X425266Y-687769D01*
X425213Y-688103D01*
X425266Y-688436D01*
X425373Y-688686D01*
X425533Y-688853D01*
X425720Y-688936D01*
X425906Y-688894D01*
X426066Y-688769D01*
X426173Y-688603D01*
G01X427520Y-688936D02*
Y-687269D01*
G01Y-687603D02*
X427653Y-687436D01*
X427786Y-687311D01*
X427973Y-687269D01*
X428106Y-687311D01*
X428266Y-687436D01*
G01X430573Y-686436D02*
Y-688936D01*
G01Y-688561D02*
X430466Y-688769D01*
X430306Y-688894D01*
X430120Y-688936D01*
X429906Y-688853D01*
X429746Y-688644D01*
X429640Y-688394D01*
X429613Y-688103D01*
X429640Y-687811D01*
X429746Y-687561D01*
X429906Y-687353D01*
X430120Y-687269D01*
X430306Y-687311D01*
X430440Y-687394D01*
X430573Y-687561D01*
G01X433960Y-688936D02*
Y-686436D01*
X434626D01*
X434840Y-686561D01*
X434973Y-686728D01*
X435026Y-687061D01*
X434973Y-687394D01*
X434813Y-687603D01*
X434626Y-687728D01*
X433960D01*
G01X434626D02*
X435026Y-688936D01*
G01X436293Y-687811D02*
X437146D01*
X437066Y-687519D01*
X436933Y-687353D01*
X436746Y-687269D01*
X436560Y-687311D01*
X436400Y-687436D01*
X436293Y-687728D01*
X436240Y-687978D01*
Y-688228D01*
X436293Y-688478D01*
X436426Y-688728D01*
X436586Y-688894D01*
X436773Y-688936D01*
X436960Y-688853D01*
X437146Y-688603D01*
G01X438413Y-687269D02*
X438893Y-688936D01*
X439373Y-687269D01*
G01X441093Y-689019D02*
X441040Y-688978D01*
Y-688894D01*
X441093Y-688853D01*
X441146Y-688894D01*
Y-688978D01*
X441093Y-689019D01*
G01X443613Y-688936D02*
Y-686436D01*
X442626Y-688228D01*
X443960D01*
G01X444826Y-688936D02*
X445493Y-686436D01*
X446160Y-688936D01*
G01X445920Y-688061D02*
X445066D01*
G01X408593Y-661936D02*
Y-666936D01*
G01X407136Y-661936D02*
X410050D01*
G01X413693Y-666936D02*
X413313Y-666853D01*
X412933Y-666519D01*
X412680Y-665936D01*
X412553Y-665269D01*
X412680Y-664603D01*
X412933Y-664019D01*
X413313Y-663686D01*
X413693Y-663603D01*
X414073Y-663686D01*
X414453Y-664019D01*
X414706Y-664603D01*
X414770Y-665269D01*
X414706Y-665936D01*
X414453Y-666519D01*
X414073Y-666853D01*
X413693Y-666936D01*
G01X418793D02*
X418413Y-666853D01*
X418033Y-666519D01*
X417780Y-665936D01*
X417653Y-665269D01*
X417780Y-664603D01*
X418033Y-664019D01*
X418413Y-663686D01*
X418793Y-663603D01*
X419173Y-663686D01*
X419553Y-664019D01*
X419806Y-664603D01*
X419870Y-665269D01*
X419806Y-665936D01*
X419553Y-666519D01*
X419173Y-666853D01*
X418793Y-666936D01*
G01X423893D02*
Y-661936D01*
G01X428993Y-667103D02*
X428866Y-667019D01*
Y-666853D01*
X428993Y-666769D01*
X429120Y-666853D01*
Y-667019D01*
X428993Y-667103D01*
G01Y-664853D02*
X428866Y-664769D01*
Y-664603D01*
X428993Y-664519D01*
X429120Y-664603D01*
Y-664769D01*
X428993Y-664853D01*
G01X407326Y-641936D02*
Y-636936D01*
X408910D01*
X409416Y-637186D01*
X409733Y-637519D01*
X409860Y-638186D01*
X409733Y-638853D01*
X409353Y-639269D01*
X408910Y-639519D01*
X407326D01*
G01X408910D02*
X409860Y-641936D01*
G01X414960D02*
X412426D01*
Y-636936D01*
X414960D01*
G01X413946Y-639353D02*
X412426D01*
G01X417210Y-636936D02*
X418793Y-641936D01*
X420376Y-636936D01*
G01X423893Y-642103D02*
X423766Y-642019D01*
Y-641853D01*
X423893Y-641769D01*
X424020Y-641853D01*
Y-642019D01*
X423893Y-642103D01*
G01Y-639853D02*
X423766Y-639769D01*
Y-639603D01*
X423893Y-639519D01*
X424020Y-639603D01*
Y-639769D01*
X423893Y-639853D01*
G01X2010999Y-388000D02*
Y1475775D01*
X-407000D01*
Y-386798D01*
Y-755294D01*
Y-793716D01*
X-368578D01*
X1942346D01*
X2010999D01*
Y-725063D01*
Y-388000D01*
G01X-42602Y-671096D02*
X-41975Y-671621D01*
X-41270Y-671936D01*
X-40644D01*
X-40017Y-671621D01*
X-39547Y-671096D01*
X-39312Y-670361D01*
X-39469Y-669626D01*
X-39860Y-668996D01*
X-40565Y-668576D01*
X-41505Y-668366D01*
X-42054Y-667946D01*
X-42289Y-667211D01*
X-42132Y-666476D01*
X-41740Y-665951D01*
X-41192Y-665636D01*
X-40644D01*
X-40095Y-665846D01*
X-39625Y-666371D01*
G01X-36302Y-671936D02*
Y-665636D01*
G01X-33012D02*
Y-671936D01*
G01Y-668786D02*
X-36302D01*
G01X-29297Y-665636D02*
X-27417D01*
G01X-28357D02*
Y-671936D01*
G01X-29297D02*
X-27417D01*
G01X-20490D02*
X-23624D01*
Y-665636D01*
X-20490D01*
G01X-21744Y-668681D02*
X-23624D01*
G01X-17559Y-671936D02*
Y-665636D01*
X-13955Y-671936D01*
Y-665636D01*
G01X-9614Y-673091D02*
X-9300Y-671726D01*
G01X-3157Y-665636D02*
Y-671936D01*
G01X-4959Y-665636D02*
X-1355D01*
G01X1185Y-671936D02*
X3143Y-665636D01*
X5101Y-671936D01*
G01X4396Y-669731D02*
X1890D01*
G01X8503Y-665636D02*
X10383D01*
G01X9443D02*
Y-671936D01*
G01X8503D02*
X10383D01*
G01X13393Y-665636D02*
X14490Y-671936D01*
X15743Y-665636D01*
X16996Y-671936D01*
X18093Y-665636D01*
G01X20085Y-671936D02*
X22043Y-665636D01*
X24001Y-671936D01*
G01X23296Y-669731D02*
X20790D01*
G01X26541Y-671936D02*
Y-665636D01*
X30145Y-671936D01*
Y-665636D01*
G01X39376Y-671936D02*
Y-665636D01*
X41335D01*
X41961Y-665951D01*
X42353Y-666371D01*
X42510Y-667211D01*
X42353Y-668051D01*
X41883Y-668576D01*
X41335Y-668891D01*
X39376D01*
G01X41335D02*
X42510Y-671936D01*
G01X47243Y-672146D02*
X47086Y-672041D01*
Y-671831D01*
X47243Y-671726D01*
X47400Y-671831D01*
Y-672041D01*
X47243Y-672146D01*
G01X53543Y-671936D02*
X52916Y-671831D01*
X52368Y-671411D01*
X51898Y-670781D01*
X51585Y-670046D01*
X51428Y-669206D01*
Y-668366D01*
X51585Y-667526D01*
X51898Y-666791D01*
X52368Y-666161D01*
X52916Y-665741D01*
X53543Y-665636D01*
X54170Y-665741D01*
X54718Y-666161D01*
X55188Y-666791D01*
X55501Y-667526D01*
X55658Y-668366D01*
Y-669206D01*
X55501Y-670046D01*
X55188Y-670781D01*
X54718Y-671411D01*
X54170Y-671831D01*
X53543Y-671936D01*
G01X59843Y-672146D02*
X59686Y-672041D01*
Y-671831D01*
X59843Y-671726D01*
X60000Y-671831D01*
Y-672041D01*
X59843Y-672146D01*
G01X67866Y-666161D02*
X67396Y-665846D01*
X66848Y-665636D01*
X66221D01*
X65516Y-665951D01*
X64968Y-666476D01*
X64576Y-667106D01*
X64263Y-668156D01*
X64185Y-669101D01*
X64341Y-670046D01*
X64576Y-670676D01*
X65046Y-671306D01*
X65595Y-671726D01*
X66143Y-671936D01*
X66691D01*
X67240Y-671726D01*
X67710Y-671411D01*
X68101Y-670991D01*
G01X72443Y-672146D02*
X72286Y-672041D01*
Y-671831D01*
X72443Y-671726D01*
X72600Y-671831D01*
Y-672041D01*
X72443Y-672146D01*
G01X-42680Y-661936D02*
Y-655636D01*
G01X-39704D02*
X-42680Y-659521D01*
G01X-39234Y-661936D02*
X-41349Y-657736D01*
G01X-36380Y-655636D02*
Y-660151D01*
X-36067Y-661096D01*
X-35440Y-661726D01*
X-34657Y-661936D01*
X-33874Y-661726D01*
X-33247Y-661096D01*
X-32934Y-660151D01*
Y-655636D01*
G01X-26790Y-661936D02*
X-29924D01*
Y-655636D01*
X-26790D01*
G01X-28044Y-658681D02*
X-29924D01*
G01X-22997Y-655636D02*
X-21117D01*
G01X-22057D02*
Y-661936D01*
G01X-22997D02*
X-21117D01*
G01X-11102Y-661096D02*
X-10475Y-661621D01*
X-9770Y-661936D01*
X-9144D01*
X-8517Y-661621D01*
X-8047Y-661096D01*
X-7812Y-660361D01*
X-7969Y-659626D01*
X-8360Y-658996D01*
X-9065Y-658576D01*
X-10005Y-658366D01*
X-10554Y-657946D01*
X-10789Y-657211D01*
X-10632Y-656476D01*
X-10240Y-655951D01*
X-9692Y-655636D01*
X-9144D01*
X-8595Y-655846D01*
X-8125Y-656371D01*
G01X-4802Y-661936D02*
Y-655636D01*
G01X-1512D02*
Y-661936D01*
G01Y-658786D02*
X-4802D01*
G01X1185Y-661936D02*
X3143Y-655636D01*
X5101Y-661936D01*
G01X4396Y-659731D02*
X1890D01*
G01X7641Y-661936D02*
Y-655636D01*
X11245Y-661936D01*
Y-655636D01*
G01X20398Y-661936D02*
Y-655636D01*
G01X23688D02*
Y-661936D01*
G01Y-658786D02*
X20398D01*
G01X26698Y-661096D02*
X27325Y-661621D01*
X28030Y-661936D01*
X28656D01*
X29283Y-661621D01*
X29753Y-661096D01*
X29988Y-660361D01*
X29831Y-659626D01*
X29440Y-658996D01*
X28735Y-658576D01*
X27795Y-658366D01*
X27246Y-657946D01*
X27011Y-657211D01*
X27168Y-656476D01*
X27560Y-655951D01*
X28108Y-655636D01*
X28656D01*
X29205Y-655846D01*
X29675Y-656371D01*
G01X33703Y-655636D02*
X35583D01*
G01X34643D02*
Y-661936D01*
G01X33703D02*
X35583D01*
G01X38985D02*
X40943Y-655636D01*
X42901Y-661936D01*
G01X42196Y-659731D02*
X39690D01*
G01X45441Y-661936D02*
Y-655636D01*
X49045Y-661936D01*
Y-655636D01*
G01X54013Y-658786D02*
X55580D01*
Y-660676D01*
X55110Y-661306D01*
X54561Y-661726D01*
X53778Y-661936D01*
X52995Y-661726D01*
X52446Y-661306D01*
X51976Y-660676D01*
X51663Y-659941D01*
X51506Y-659101D01*
Y-658366D01*
X51663Y-657736D01*
X51976Y-657001D01*
X52446Y-656371D01*
X52916Y-655951D01*
X53543Y-655636D01*
X54091D01*
X54718Y-655846D01*
X55188Y-656266D01*
G01X59686Y-663091D02*
X60000Y-661726D01*
G01X66143Y-655636D02*
Y-661936D01*
G01X64341Y-655636D02*
X67945D01*
G01X70485Y-661936D02*
X72443Y-655636D01*
X74401Y-661936D01*
G01X73696Y-659731D02*
X71190D01*
G01X78743Y-661936D02*
X78116Y-661831D01*
X77568Y-661411D01*
X77098Y-660781D01*
X76785Y-660046D01*
X76628Y-659206D01*
Y-658366D01*
X76785Y-657526D01*
X77098Y-656791D01*
X77568Y-656161D01*
X78116Y-655741D01*
X78743Y-655636D01*
X79370Y-655741D01*
X79918Y-656161D01*
X80388Y-656791D01*
X80701Y-657526D01*
X80858Y-658366D01*
Y-659206D01*
X80701Y-660046D01*
X80388Y-660781D01*
X79918Y-661411D01*
X79370Y-661831D01*
X78743Y-661936D01*
G01X91343D02*
Y-659101D01*
X89776Y-655636D01*
G01X92910D02*
X91343Y-659101D01*
G01X95920Y-655636D02*
Y-660151D01*
X96233Y-661096D01*
X96860Y-661726D01*
X97643Y-661936D01*
X98426Y-661726D01*
X99053Y-661096D01*
X99366Y-660151D01*
Y-655636D01*
G01X101985Y-661936D02*
X103943Y-655636D01*
X105901Y-661936D01*
G01X105196Y-659731D02*
X102690D01*
G01X108441Y-661936D02*
Y-655636D01*
X112045Y-661936D01*
Y-655636D01*
G01X-42759Y-651936D02*
Y-645636D01*
X-39155Y-651936D01*
Y-645636D01*
G01X-34657Y-651936D02*
X-35284Y-651831D01*
X-35832Y-651411D01*
X-36302Y-650781D01*
X-36615Y-650046D01*
X-36772Y-649206D01*
Y-648366D01*
X-36615Y-647526D01*
X-36302Y-646791D01*
X-35832Y-646161D01*
X-35284Y-645741D01*
X-34657Y-645636D01*
X-34030Y-645741D01*
X-33482Y-646161D01*
X-33012Y-646791D01*
X-32699Y-647526D01*
X-32542Y-648366D01*
Y-649206D01*
X-32699Y-650046D01*
X-33012Y-650781D01*
X-33482Y-651411D01*
X-34030Y-651831D01*
X-34657Y-651936D01*
G01X-28357Y-652146D02*
X-28514Y-652041D01*
Y-651831D01*
X-28357Y-651726D01*
X-28200Y-651831D01*
Y-652041D01*
X-28357Y-652146D01*
G01X-22057Y-651936D02*
Y-645636D01*
X-22997Y-646896D01*
G01Y-651936D02*
X-21117D01*
G01X-15757D02*
X-15209Y-651831D01*
X-14582Y-651516D01*
X-14190Y-650991D01*
X-14034Y-650256D01*
X-14190Y-649521D01*
X-14660Y-648891D01*
X-15365Y-648576D01*
X-16149D01*
X-16619Y-648366D01*
X-17010Y-647841D01*
X-17167Y-647106D01*
X-16932Y-646371D01*
X-16384Y-645846D01*
X-15757Y-645636D01*
X-15130Y-645846D01*
X-14582Y-646371D01*
X-14347Y-647106D01*
X-14504Y-647841D01*
X-14895Y-648366D01*
X-15365Y-648576D01*
X-16149D01*
X-16854Y-648891D01*
X-17324Y-649521D01*
X-17480Y-650256D01*
X-17324Y-650991D01*
X-16932Y-651516D01*
X-16305Y-651831D01*
X-15757Y-651936D01*
G01X-9457D02*
X-8909Y-651831D01*
X-8282Y-651516D01*
X-7890Y-650991D01*
X-7734Y-650256D01*
X-7890Y-649521D01*
X-8360Y-648891D01*
X-9065Y-648576D01*
X-9849D01*
X-10319Y-648366D01*
X-10710Y-647841D01*
X-10867Y-647106D01*
X-10632Y-646371D01*
X-10084Y-645846D01*
X-9457Y-645636D01*
X-8830Y-645846D01*
X-8282Y-646371D01*
X-8047Y-647106D01*
X-8204Y-647841D01*
X-8595Y-648366D01*
X-9065Y-648576D01*
X-9849D01*
X-10554Y-648891D01*
X-11024Y-649521D01*
X-11180Y-650256D01*
X-11024Y-650991D01*
X-10632Y-651516D01*
X-10005Y-651831D01*
X-9457Y-651936D01*
G01X-3314Y-653091D02*
X-3000Y-651726D01*
G01X793Y-645636D02*
X1890Y-651936D01*
X3143Y-645636D01*
X4396Y-651936D01*
X5493Y-645636D01*
G01X11010Y-651936D02*
X7876D01*
Y-645636D01*
X11010D01*
G01X9756Y-648681D02*
X7876D01*
G01X13941Y-651936D02*
Y-645636D01*
X17545Y-651936D01*
Y-645636D01*
G01X26698Y-651936D02*
Y-645636D01*
G01X29988D02*
Y-651936D01*
G01Y-648786D02*
X26698D01*
G01X32293Y-645636D02*
X33390Y-651936D01*
X34643Y-645636D01*
X35896Y-651936D01*
X36993Y-645636D01*
G01X38985Y-651936D02*
X40943Y-645636D01*
X42901Y-651936D01*
G01X42196Y-649731D02*
X39690D01*
G01X52055Y-646686D02*
X52525Y-646056D01*
X53073Y-645741D01*
X53700Y-645636D01*
X54483Y-645846D01*
X55031Y-646371D01*
X55188Y-647001D01*
X55110Y-647631D01*
X54796Y-648156D01*
X53230Y-649206D01*
X52525Y-649941D01*
X52055Y-650991D01*
X51898Y-651936D01*
X55188D01*
G01X58041D02*
Y-645636D01*
X61645Y-651936D01*
Y-645636D01*
G01X64420Y-651936D02*
Y-645636D01*
X65986D01*
X66613Y-645951D01*
X67083Y-646371D01*
X67475Y-647001D01*
X67788Y-647736D01*
X67866Y-648786D01*
X67788Y-649836D01*
X67475Y-650571D01*
X67083Y-651201D01*
X66613Y-651621D01*
X65986Y-651936D01*
X64420D01*
G01X77176D02*
Y-645636D01*
X79135D01*
X79761Y-645951D01*
X80153Y-646371D01*
X80310Y-647211D01*
X80153Y-648051D01*
X79683Y-648576D01*
X79135Y-648891D01*
X77176D01*
G01X79135D02*
X80310Y-651936D01*
G01X83320D02*
Y-645636D01*
X84886D01*
X85513Y-645951D01*
X85983Y-646371D01*
X86375Y-647001D01*
X86688Y-647736D01*
X86766Y-648786D01*
X86688Y-649836D01*
X86375Y-650571D01*
X85983Y-651201D01*
X85513Y-651621D01*
X84886Y-651936D01*
X83320D01*
G01X91343Y-652146D02*
X91186Y-652041D01*
Y-651831D01*
X91343Y-651726D01*
X91500Y-651831D01*
Y-652041D01*
X91343Y-652146D01*
G01X-18657Y-639236D02*
X-21177Y-638819D01*
X-23382Y-637153D01*
X-25272Y-634653D01*
X-26532Y-631736D01*
X-27162Y-628403D01*
Y-625069D01*
X-26532Y-621736D01*
X-25272Y-618819D01*
X-23382Y-616320D01*
X-21177Y-614653D01*
X-18657Y-614236D01*
X-16137Y-614653D01*
X-13932Y-616320D01*
X-12042Y-618819D01*
X-10782Y-621736D01*
X-10152Y-625069D01*
Y-628403D01*
X-10782Y-631736D01*
X-12042Y-634653D01*
X-13932Y-637153D01*
X-16137Y-638819D01*
X-18657Y-639236D01*
G01X-16137Y-632569D02*
X-12357Y-639236D01*
G01X1188Y-622570D02*
Y-634236D01*
X2448Y-637153D01*
X4338Y-638819D01*
X6543Y-639236D01*
X8748Y-638819D01*
X10638Y-637153D01*
X11898Y-634236D01*
G01Y-639236D02*
Y-622570D01*
G01X37413Y-639236D02*
Y-622570D01*
G01Y-625486D02*
X36153Y-623820D01*
X34263Y-622986D01*
X32058Y-622570D01*
X29853Y-623403D01*
X27963Y-625069D01*
X26703Y-627570D01*
X26073Y-630903D01*
X26703Y-634236D01*
X27963Y-636737D01*
X29853Y-638403D01*
X32058Y-639236D01*
X34263Y-638819D01*
X36153Y-637570D01*
X37413Y-635903D01*
G01X51588Y-639236D02*
Y-622570D01*
G01Y-626736D02*
X52848Y-624653D01*
X54738Y-622986D01*
X57258Y-622570D01*
X59463Y-622986D01*
X61353Y-624653D01*
X62298Y-627570D01*
Y-639236D01*
G01X82143Y-614236D02*
Y-639236D01*
G01X77733Y-622570D02*
X86553D01*
G01X113013Y-639236D02*
Y-622570D01*
G01Y-625486D02*
X111753Y-623820D01*
X109863Y-622986D01*
X107658Y-622570D01*
X105453Y-623403D01*
X103563Y-625069D01*
X102303Y-627570D01*
X101673Y-630903D01*
X102303Y-634236D01*
X103563Y-636737D01*
X105453Y-638403D01*
X107658Y-639236D01*
X109863Y-638819D01*
X111753Y-637570D01*
X113013Y-635903D01*
G01X152693Y-618936D02*
Y-626936D01*
X156693D01*
G01X164493D02*
Y-621603D01*
G01Y-622536D02*
X164093Y-622003D01*
X163493Y-621736D01*
X162793Y-621603D01*
X162093Y-621869D01*
X161493Y-622403D01*
X161093Y-623203D01*
X160893Y-624269D01*
X161093Y-625336D01*
X161493Y-626136D01*
X162093Y-626669D01*
X162793Y-626936D01*
X163493Y-626803D01*
X164093Y-626403D01*
X164493Y-625870D01*
G01X168593Y-629336D02*
X169193Y-629603D01*
X169993Y-629336D01*
X170493Y-628803D01*
X170893Y-628136D01*
X171493Y-626003D01*
X172793Y-621603D01*
G01X169593D02*
X171493Y-626003D01*
G01X177193Y-623336D02*
X180393D01*
X180093Y-622403D01*
X179593Y-621869D01*
X178893Y-621603D01*
X178193Y-621736D01*
X177593Y-622136D01*
X177193Y-623069D01*
X176993Y-623870D01*
Y-624669D01*
X177193Y-625469D01*
X177693Y-626269D01*
X178293Y-626803D01*
X178993Y-626936D01*
X179693Y-626669D01*
X180393Y-625870D01*
G01X185293Y-626936D02*
Y-621603D01*
G01Y-622669D02*
X185793Y-622136D01*
X186293Y-621736D01*
X186993Y-621603D01*
X187493Y-621736D01*
X188093Y-622136D01*
G01X164193Y-651936D02*
Y-643936D01*
X166593D01*
X167393Y-644336D01*
X167993Y-645269D01*
X168193Y-646336D01*
X167993Y-647403D01*
X167493Y-648203D01*
X166593Y-648603D01*
X164193D01*
G01X171693Y-651936D02*
X174193Y-643936D01*
X176693Y-651936D01*
G01X175793Y-649136D02*
X172593D01*
G01X180093Y-650870D02*
X180893Y-651536D01*
X181793Y-651936D01*
X182593D01*
X183393Y-651536D01*
X183993Y-650870D01*
X184293Y-649936D01*
X184093Y-649003D01*
X183593Y-648203D01*
X182693Y-647669D01*
X181493Y-647403D01*
X180793Y-646869D01*
X180493Y-645936D01*
X180693Y-645003D01*
X181193Y-644336D01*
X181893Y-643936D01*
X182593D01*
X183293Y-644203D01*
X183893Y-644869D01*
G01X190193Y-643936D02*
Y-651936D01*
G01X187893Y-643936D02*
X192493D01*
G01X196893Y-649269D02*
X199493D01*
G01X206993Y-647669D02*
X207393Y-647269D01*
X207693Y-646603D01*
X207893Y-645669D01*
X207693Y-644869D01*
X207293Y-644336D01*
X206593Y-643936D01*
X203893D01*
Y-651936D01*
X207193D01*
X207893Y-651403D01*
X208293Y-650603D01*
X208493Y-649669D01*
X208293Y-648736D01*
X207693Y-647936D01*
X206993Y-647669D01*
X203893D01*
G01X214193Y-651936D02*
X213393Y-651803D01*
X212693Y-651269D01*
X212093Y-650469D01*
X211693Y-649536D01*
X211493Y-648469D01*
Y-647403D01*
X211693Y-646336D01*
X212093Y-645403D01*
X212693Y-644603D01*
X213393Y-644069D01*
X214193Y-643936D01*
X214993Y-644069D01*
X215693Y-644603D01*
X216293Y-645403D01*
X216693Y-646336D01*
X216893Y-647403D01*
Y-648469D01*
X216693Y-649536D01*
X216293Y-650469D01*
X215693Y-651269D01*
X214993Y-651803D01*
X214193Y-651936D01*
G01X222193Y-643936D02*
Y-651936D01*
G01X219893Y-643936D02*
X224493D01*
G01X173993Y-676936D02*
Y-668936D01*
G01X177793D02*
X173993Y-673870D01*
G01X178393Y-676936D02*
X175693Y-671603D01*
G01X185993Y-676936D02*
Y-671603D01*
G01Y-672536D02*
X185593Y-672003D01*
X184993Y-671736D01*
X184293Y-671603D01*
X183593Y-671869D01*
X182993Y-672403D01*
X182593Y-673203D01*
X182393Y-674269D01*
X182593Y-675336D01*
X182993Y-676136D01*
X183593Y-676669D01*
X184293Y-676936D01*
X184993Y-676803D01*
X185593Y-676403D01*
X185993Y-675870D01*
G01X192193Y-671603D02*
Y-676936D01*
G01Y-669469D02*
X191993Y-669336D01*
Y-669069D01*
X192193Y-668936D01*
X192393Y-669069D01*
Y-669336D01*
X192193Y-669469D01*
G01X279293Y-670269D02*
X279893Y-669469D01*
X280593Y-669069D01*
X281393Y-668936D01*
X282393Y-669203D01*
X283093Y-669869D01*
X283293Y-670669D01*
X283193Y-671470D01*
X282793Y-672136D01*
X280793Y-673469D01*
X279893Y-674403D01*
X279293Y-675736D01*
X279093Y-676936D01*
X283293D01*
G01X289193Y-668936D02*
X288393Y-669203D01*
X287793Y-669869D01*
X287393Y-670669D01*
X287093Y-671736D01*
X286993Y-672936D01*
X287093Y-674136D01*
X287393Y-675203D01*
X287793Y-676003D01*
X288393Y-676669D01*
X289193Y-676936D01*
X289993Y-676669D01*
X290593Y-676003D01*
X290993Y-675203D01*
X291293Y-674136D01*
X291393Y-672936D01*
X291293Y-671736D01*
X290993Y-670669D01*
X290593Y-669869D01*
X289993Y-669203D01*
X289193Y-668936D01*
G01X295293Y-670269D02*
X295893Y-669469D01*
X296593Y-669069D01*
X297393Y-668936D01*
X298393Y-669203D01*
X299093Y-669869D01*
X299293Y-670669D01*
X299193Y-671470D01*
X298793Y-672136D01*
X296793Y-673469D01*
X295893Y-674403D01*
X295293Y-675736D01*
X295093Y-676936D01*
X299293D01*
G01X303293Y-670269D02*
X303893Y-669469D01*
X304593Y-669069D01*
X305393Y-668936D01*
X306393Y-669203D01*
X307093Y-669869D01*
X307293Y-670669D01*
X307193Y-671470D01*
X306793Y-672136D01*
X304793Y-673469D01*
X303893Y-674403D01*
X303293Y-675736D01*
X303093Y-676936D01*
X307293D01*
G01X311393Y-677203D02*
X314993Y-668936D01*
G01X321193Y-676936D02*
Y-668936D01*
X319993Y-670536D01*
G01Y-676936D02*
X322393D01*
G01X327293Y-670269D02*
X327893Y-669469D01*
X328593Y-669069D01*
X329393Y-668936D01*
X330393Y-669203D01*
X331093Y-669869D01*
X331293Y-670669D01*
X331193Y-671470D01*
X330793Y-672136D01*
X328793Y-673469D01*
X327893Y-674403D01*
X327293Y-675736D01*
X327093Y-676936D01*
X331293D01*
G01X335393Y-677203D02*
X338993Y-668936D01*
G01X345193D02*
X344393Y-669203D01*
X343793Y-669869D01*
X343393Y-670669D01*
X343093Y-671736D01*
X342993Y-672936D01*
X343093Y-674136D01*
X343393Y-675203D01*
X343793Y-676003D01*
X344393Y-676669D01*
X345193Y-676936D01*
X345993Y-676669D01*
X346593Y-676003D01*
X346993Y-675203D01*
X347293Y-674136D01*
X347393Y-672936D01*
X347293Y-671736D01*
X346993Y-670669D01*
X346593Y-669869D01*
X345993Y-669203D01*
X345193Y-668936D01*
G01X351493Y-676003D02*
X352193Y-676669D01*
X352993Y-676936D01*
X353793Y-676669D01*
X354493Y-675870D01*
X354993Y-674669D01*
X355193Y-673469D01*
Y-672003D01*
X354993Y-670803D01*
X354493Y-669736D01*
X353893Y-669203D01*
X353193Y-668936D01*
X352393Y-669203D01*
X351793Y-669736D01*
X351393Y-670536D01*
X351193Y-671603D01*
X351393Y-672536D01*
X351893Y-673469D01*
X352493Y-674003D01*
X353193Y-674136D01*
X353993Y-673870D01*
X354593Y-673203D01*
X355193Y-672003D01*
G01X278993Y-651936D02*
Y-643936D01*
X280993D01*
X281793Y-644336D01*
X282393Y-644869D01*
X282893Y-645669D01*
X283293Y-646603D01*
X283393Y-647936D01*
X283293Y-649269D01*
X282893Y-650203D01*
X282393Y-651003D01*
X281793Y-651536D01*
X280993Y-651936D01*
X278993D01*
G01X286693D02*
X289193Y-643936D01*
X291693Y-651936D01*
G01X290793Y-649136D02*
X287593D01*
G01X297193Y-643936D02*
X296393Y-644203D01*
X295793Y-644869D01*
X295393Y-645669D01*
X295093Y-646736D01*
X294993Y-647936D01*
X295093Y-649136D01*
X295393Y-650203D01*
X295793Y-651003D01*
X296393Y-651669D01*
X297193Y-651936D01*
X297993Y-651669D01*
X298593Y-651003D01*
X298993Y-650203D01*
X299293Y-649136D01*
X299393Y-647936D01*
X299293Y-646736D01*
X298993Y-645669D01*
X298593Y-644869D01*
X297993Y-644203D01*
X297193Y-643936D01*
G01X303293Y-651936D02*
Y-643936D01*
X307093D01*
G01X305693Y-647803D02*
X303293D01*
G01X313193Y-643936D02*
X312393Y-644203D01*
X311793Y-644869D01*
X311393Y-645669D01*
X311093Y-646736D01*
X310993Y-647936D01*
X311093Y-649136D01*
X311393Y-650203D01*
X311793Y-651003D01*
X312393Y-651669D01*
X313193Y-651936D01*
X313993Y-651669D01*
X314593Y-651003D01*
X314993Y-650203D01*
X315293Y-649136D01*
X315393Y-647936D01*
X315293Y-646736D01*
X314993Y-645669D01*
X314593Y-644869D01*
X313993Y-644203D01*
X313193Y-643936D01*
G01X321193D02*
Y-651936D01*
G01X318893Y-643936D02*
X323493D01*
G01X326593Y-651936D02*
Y-643936D01*
X329193Y-650603D01*
X331793Y-643936D01*
Y-651936D01*
G01X334993D02*
Y-643936D01*
X336993D01*
X337793Y-644336D01*
X338393Y-644869D01*
X338893Y-645669D01*
X339293Y-646603D01*
X339393Y-647936D01*
X339293Y-649269D01*
X338893Y-650203D01*
X338393Y-651003D01*
X337793Y-651536D01*
X336993Y-651936D01*
X334993D01*
G01X347393Y-644603D02*
X346793Y-644203D01*
X346093Y-643936D01*
X345293D01*
X344393Y-644336D01*
X343693Y-645003D01*
X343193Y-645803D01*
X342793Y-647136D01*
X342693Y-648336D01*
X342893Y-649536D01*
X343193Y-650336D01*
X343793Y-651136D01*
X344493Y-651669D01*
X345193Y-651936D01*
X345893D01*
X346593Y-651669D01*
X347193Y-651269D01*
X347693Y-650736D01*
G01X350993Y-651936D02*
Y-643936D01*
X352993D01*
X353793Y-644336D01*
X354393Y-644869D01*
X354893Y-645669D01*
X355293Y-646603D01*
X355393Y-647936D01*
X355293Y-649269D01*
X354893Y-650203D01*
X354393Y-651003D01*
X353793Y-651536D01*
X352993Y-651936D01*
X350993D01*
G01X361193Y-643936D02*
X360393Y-644203D01*
X359793Y-644869D01*
X359393Y-645669D01*
X359093Y-646736D01*
X358993Y-647936D01*
X359093Y-649136D01*
X359393Y-650203D01*
X359793Y-651003D01*
X360393Y-651669D01*
X361193Y-651936D01*
X361993Y-651669D01*
X362593Y-651003D01*
X362993Y-650203D01*
X363293Y-649136D01*
X363393Y-647936D01*
X363293Y-646736D01*
X362993Y-645669D01*
X362593Y-644869D01*
X361993Y-644203D01*
X361193Y-643936D01*
G01X298418Y-624819D02*
Y-618519D01*
X301394D01*
G01X300298Y-621564D02*
X298418D01*
G01X306206Y-618519D02*
X305579Y-618729D01*
X305109Y-619254D01*
X304796Y-619884D01*
X304561Y-620724D01*
X304483Y-621669D01*
X304561Y-622614D01*
X304796Y-623454D01*
X305109Y-624084D01*
X305579Y-624609D01*
X306206Y-624819D01*
X306833Y-624609D01*
X307303Y-624084D01*
X307616Y-623454D01*
X307851Y-622614D01*
X307929Y-621669D01*
X307851Y-620724D01*
X307616Y-619884D01*
X307303Y-619254D01*
X306833Y-618729D01*
X306206Y-618519D01*
G01X312506D02*
Y-624819D01*
G01X310704Y-618519D02*
X314308D01*
G01X316456Y-626919D02*
X321156D01*
G01X323069Y-624819D02*
Y-618519D01*
X325106Y-623769D01*
X327143Y-618519D01*
Y-624819D01*
G01X332816D02*
Y-620619D01*
G01Y-621354D02*
X332503Y-620934D01*
X332033Y-620724D01*
X331484Y-620619D01*
X330936Y-620829D01*
X330466Y-621249D01*
X330153Y-621879D01*
X329996Y-622719D01*
X330153Y-623559D01*
X330466Y-624189D01*
X330936Y-624609D01*
X331484Y-624819D01*
X332033Y-624714D01*
X332503Y-624399D01*
X332816Y-623979D01*
G01X336374Y-624819D02*
Y-620619D01*
G01Y-621669D02*
X336688Y-621144D01*
X337158Y-620724D01*
X337784Y-620619D01*
X338333Y-620724D01*
X338803Y-621144D01*
X339038Y-621879D01*
Y-624819D01*
G01X345416D02*
Y-620619D01*
G01Y-621354D02*
X345103Y-620934D01*
X344633Y-620724D01*
X344084Y-620619D01*
X343536Y-620829D01*
X343066Y-621249D01*
X342753Y-621879D01*
X342596Y-622719D01*
X342753Y-623559D01*
X343066Y-624189D01*
X343536Y-624609D01*
X344084Y-624819D01*
X344633Y-624714D01*
X345103Y-624399D01*
X345416Y-623979D01*
G01X349209Y-626394D02*
X349758Y-626814D01*
X350384Y-626919D01*
X350933Y-626814D01*
X351403Y-626289D01*
X351716Y-625554D01*
Y-620619D01*
G01Y-621459D02*
X351403Y-621039D01*
X350933Y-620724D01*
X350384Y-620619D01*
X349758Y-620829D01*
X349366Y-621249D01*
X349053Y-621984D01*
X348896Y-622719D01*
X348974Y-623349D01*
X349288Y-624084D01*
X349758Y-624609D01*
X350384Y-624819D01*
X350854Y-624714D01*
X351403Y-624294D01*
X351716Y-623874D01*
G01X355431Y-621984D02*
X357938D01*
X357703Y-621249D01*
X357311Y-620829D01*
X356763Y-620619D01*
X356214Y-620724D01*
X355744Y-621039D01*
X355431Y-621774D01*
X355274Y-622404D01*
Y-623034D01*
X355431Y-623664D01*
X355823Y-624294D01*
X356293Y-624714D01*
X356841Y-624819D01*
X357389Y-624609D01*
X357938Y-623979D01*
G01X360556Y-624819D02*
Y-620619D01*
G01Y-621774D02*
X360791Y-621249D01*
X361183Y-620829D01*
X361731Y-620619D01*
X362279Y-620829D01*
X362671Y-621249D01*
X362906Y-621774D01*
Y-624819D01*
G01Y-621774D02*
X363141Y-621249D01*
X363533Y-620829D01*
X364081Y-620619D01*
X364629Y-620829D01*
X365021Y-621249D01*
X365256Y-621879D01*
Y-624819D01*
G01X368031Y-621984D02*
X370538D01*
X370303Y-621249D01*
X369911Y-620829D01*
X369363Y-620619D01*
X368814Y-620724D01*
X368344Y-621039D01*
X368031Y-621774D01*
X367874Y-622404D01*
Y-623034D01*
X368031Y-623664D01*
X368423Y-624294D01*
X368893Y-624714D01*
X369441Y-624819D01*
X369989Y-624609D01*
X370538Y-623979D01*
G01X374174Y-624819D02*
Y-620619D01*
G01Y-621669D02*
X374488Y-621144D01*
X374958Y-620724D01*
X375584Y-620619D01*
X376133Y-620724D01*
X376603Y-621144D01*
X376838Y-621879D01*
Y-624819D01*
G01X381806Y-618519D02*
Y-624819D01*
G01X380709Y-620619D02*
X382903D01*
G01X385756Y-626919D02*
X390456D01*
G01X395033Y-621459D02*
X395346Y-621144D01*
X395581Y-620619D01*
X395738Y-619884D01*
X395581Y-619254D01*
X395268Y-618834D01*
X394719Y-618519D01*
X392604D01*
Y-624819D01*
X395189D01*
X395738Y-624399D01*
X396051Y-623769D01*
X396208Y-623034D01*
X396051Y-622299D01*
X395581Y-621669D01*
X395033Y-621459D01*
X392604D01*
G01X398983Y-624819D02*
Y-618519D01*
X400549D01*
X401176Y-618834D01*
X401646Y-619254D01*
X402038Y-619884D01*
X402351Y-620619D01*
X402429Y-621669D01*
X402351Y-622719D01*
X402038Y-623454D01*
X401646Y-624084D01*
X401176Y-624504D01*
X400549Y-624819D01*
X398983D01*
G01X367693Y-679936D02*
Y-671936D01*
X366493Y-673536D01*
G01Y-679936D02*
X368893D01*
G01X373793Y-676603D02*
X374493Y-675669D01*
X375093Y-675136D01*
X375893Y-674869D01*
X376593Y-675136D01*
X377093Y-675669D01*
X377493Y-676469D01*
X377593Y-677403D01*
X377493Y-678203D01*
X377093Y-679003D01*
X376493Y-679669D01*
X375793Y-679936D01*
X374993Y-679669D01*
X374293Y-678870D01*
X373893Y-677669D01*
X373793Y-676336D01*
X373993Y-674603D01*
X374293Y-673669D01*
X374793Y-672736D01*
X375493Y-672069D01*
X376193Y-671936D01*
X376893Y-672203D01*
X377393Y-672869D01*
G01X383693Y-680203D02*
X383493Y-680069D01*
Y-679803D01*
X383693Y-679669D01*
X383893Y-679803D01*
Y-680069D01*
X383693Y-680203D01*
G01X389793Y-676603D02*
X390493Y-675669D01*
X391093Y-675136D01*
X391893Y-674869D01*
X392593Y-675136D01*
X393093Y-675669D01*
X393493Y-676469D01*
X393593Y-677403D01*
X393493Y-678203D01*
X393093Y-679003D01*
X392493Y-679669D01*
X391793Y-679936D01*
X390993Y-679669D01*
X390293Y-678870D01*
X389893Y-677669D01*
X389793Y-676336D01*
X389993Y-674603D01*
X390293Y-673669D01*
X390793Y-672736D01*
X391493Y-672069D01*
X392193Y-671936D01*
X392893Y-672203D01*
X393393Y-672869D01*
G01X412693Y-679936D02*
Y-671936D01*
X411493Y-673536D01*
G01Y-679936D02*
X413893D01*
G01X420493D02*
X420693Y-678203D01*
X420993Y-676736D01*
X421393Y-675403D01*
X421893Y-673936D01*
X422693Y-671936D01*
X418693D01*
G01X428693Y-680203D02*
X428493Y-680069D01*
Y-679803D01*
X428693Y-679669D01*
X428893Y-679803D01*
Y-680069D01*
X428693Y-680203D01*
G01X434793Y-673269D02*
X435393Y-672469D01*
X436093Y-672069D01*
X436893Y-671936D01*
X437893Y-672203D01*
X438593Y-672869D01*
X438793Y-673669D01*
X438693Y-674470D01*
X438293Y-675136D01*
X436293Y-676469D01*
X435393Y-677403D01*
X434793Y-678736D01*
X434593Y-679936D01*
X438793D01*
G01X432493Y-654936D02*
Y-646936D01*
X434493D01*
X435293Y-647336D01*
X435893Y-647869D01*
X436393Y-648669D01*
X436793Y-649603D01*
X436893Y-650936D01*
X436793Y-652269D01*
X436393Y-653203D01*
X435893Y-654003D01*
X435293Y-654536D01*
X434493Y-654936D01*
X432493D01*
G54D25*
X48500Y396276D03*
Y405724D03*
G54D34*
X59949Y398551D03*
X64051Y394449D03*
G54D52*
X126610Y377576D03*
X134090D03*
Y387024D03*
X130350D03*
X126610D03*
X256510Y368576D03*
Y378024D03*
X260250Y368576D03*
X263990D03*
Y378024D03*
X260250D03*
G54D61*
X154842Y365153D03*
Y363185D03*
X171378Y365153D03*
Y363185D03*
G54D43*
X107936Y390478D03*
X103450Y391450D03*
G54D16*
X20083Y105500D03*
X19783Y116200D03*
X48383Y106200D03*
X49983Y376000D03*
Y384000D03*
Y388000D03*
Y380000D03*
X71983Y76500D03*
X69123Y335220D03*
X99983Y360000D03*
Y364000D03*
X116383Y109300D03*
X109008Y341649D03*
X109083Y337700D03*
X117583Y366600D03*
X117502Y362623D03*
X121083Y376800D03*
X135383Y84300D03*
X137083Y195600D03*
X127283Y234800D03*
Y238300D03*
X133983Y277000D03*
X130483Y361500D03*
X152943Y141056D03*
X138683Y250700D03*
X148733Y397500D03*
Y408000D03*
X167704Y157290D03*
X166833Y161150D03*
X166704Y181735D03*
X156503Y175720D03*
X166704Y185952D03*
Y190725D03*
X158691Y189082D03*
Y192582D03*
X160583Y228732D03*
X158208Y232300D03*
X157574Y242629D03*
X166515Y238479D03*
X171913Y212033D03*
X169583Y228400D03*
X172483Y267000D03*
X170417Y281848D03*
X187864Y194343D03*
X189869Y295096D03*
X188183Y300300D03*
X184983Y422800D03*
X212239Y178269D03*
X204471Y172304D03*
X210170Y194450D03*
X210313Y203530D03*
X199281Y217208D03*
X201714Y286781D03*
X209716Y278739D03*
X201983Y300400D03*
X222964Y172340D03*
Y176346D03*
X223260Y181892D03*
X224695Y193882D03*
X226073Y200555D03*
X225827Y210143D03*
X225693Y204555D03*
X218504Y216030D03*
X216739Y286782D03*
Y282756D03*
X225349Y275773D03*
X233983Y71000D03*
X239483Y109760D03*
X241890Y182782D03*
X235937Y194151D03*
X231578Y188938D03*
X240315Y205261D03*
X232691Y207040D03*
X236376Y283911D03*
X229376Y285912D03*
X233336Y275841D03*
Y279853D03*
X229462Y289941D03*
X235283Y306900D03*
X245083Y71900D03*
X256579Y158751D03*
X242942Y194151D03*
X256059Y203097D03*
X253310Y280778D03*
X253283Y359100D03*
Y355200D03*
X271483Y53000D03*
Y57000D03*
X271493Y117366D03*
X281285Y117391D03*
X283613Y175635D03*
X281147Y209511D03*
Y213530D03*
X288527Y165802D03*
X290920Y187914D03*
X293197Y393332D03*
X315883Y122000D03*
X306483Y131290D03*
X304565Y181885D03*
Y185885D03*
X316517Y188372D03*
X314788Y216137D03*
X311483Y373000D03*
X305733Y393352D03*
Y397382D03*
X328913Y159411D03*
X320892Y161378D03*
Y165378D03*
Y157378D03*
X328913Y179411D03*
Y183411D03*
Y187411D03*
Y191411D03*
X321913Y183411D03*
X337398Y104676D03*
Y112708D03*
Y108692D03*
X337308Y186961D03*
G54D62*
X161296Y391448D03*
Y404244D03*
Y401685D03*
Y399125D03*
Y396566D03*
Y394007D03*
Y409362D03*
Y406803D03*
X181179Y316084D03*
Y313524D03*
Y310965D03*
Y308406D03*
Y305847D03*
Y323761D03*
Y321202D03*
Y318643D03*
X184296Y391448D03*
Y394007D03*
Y396566D03*
Y399125D03*
Y401685D03*
Y404244D03*
Y406803D03*
Y409362D03*
X204179Y305847D03*
Y308406D03*
Y310965D03*
Y313524D03*
Y316084D03*
Y318643D03*
Y321202D03*
Y323761D03*
X215420Y344273D03*
Y341714D03*
Y339155D03*
Y359628D03*
Y357069D03*
Y354510D03*
Y351950D03*
Y349391D03*
Y346832D03*
Y367305D03*
Y364746D03*
Y362187D03*
X238420Y339155D03*
Y341714D03*
Y344273D03*
Y346832D03*
Y349391D03*
Y351950D03*
Y354510D03*
Y357069D03*
Y359628D03*
Y362187D03*
Y364746D03*
Y367305D03*
G54D44*
X107500Y404400D03*
Y398600D03*
X137500Y123100D03*
Y128900D03*
X129928Y144932D03*
Y139132D03*
X129795Y150150D03*
Y155950D03*
X216066Y211321D03*
Y205521D03*
X266570Y131569D03*
Y137369D03*
X272311Y148785D03*
Y142985D03*
X272057Y254604D03*
Y260404D03*
X270200Y372000D03*
Y366200D03*
X277731Y148785D03*
Y142985D03*
X281000Y160100D03*
Y165900D03*
X283478Y225651D03*
Y231451D03*
X278153Y254604D03*
X283990Y254605D03*
X278153Y260404D03*
X283990Y260405D03*
X300157Y217162D03*
Y222962D03*
X294528Y221264D03*
Y227064D03*
X289102Y225598D03*
Y231398D03*
X326000Y126100D03*
Y131900D03*
X330500Y228300D03*
X322000Y235400D03*
Y229600D03*
X330500Y234100D03*
G54D17*
X27660Y106641D03*
Y111759D03*
Y109200D03*
X35140Y106641D03*
Y109200D03*
Y111759D03*
G54D53*
X150900Y12657D03*
X171400D03*
X230500Y79457D03*
X245000D03*
G54D26*
X63898Y24764D03*
X90472D03*
X117047D03*
X211142D03*
X237717D03*
G54D35*
X73898D03*
X100472D03*
X127047D03*
X221142D03*
X247717D03*
G54D36*
X79000Y90760D03*
X70500D03*
X79000Y98240D03*
X70500D03*
X86500Y90760D03*
Y98240D03*
X95700Y90760D03*
Y98240D03*
G54D27*
X53441Y91260D03*
X56000D03*
X58559D03*
Y98740D03*
X53441D03*
G54D18*
X25000Y240500D03*
X32000D03*
X166077Y327640D03*
X162077Y336440D03*
X170077D03*
G54D63*
X178355Y87450D03*
Y83710D03*
Y79970D03*
X187803D03*
Y87450D03*
G54D54*
X147947Y12657D03*
Y19743D03*
X168447Y12657D03*
X153853D03*
X168447Y19743D03*
X153853D03*
X174353Y12657D03*
Y19743D03*
X227547Y86543D03*
Y79457D03*
X242047Y86543D03*
Y79457D03*
X233453Y86543D03*
Y79457D03*
X247953Y86543D03*
Y79457D03*
G54D45*
X105549Y393549D03*
X110035Y392577D03*
G54D28*
X61661Y247701D03*
Y265299D03*
X64220Y247701D03*
X66780D03*
X69339D03*
Y265299D03*
X66780D03*
X64220D03*
G54D37*
X77761Y301897D03*
Y308393D03*
X86029Y301897D03*
Y308393D03*
G54D64*
X177037Y418500D03*
X169163Y414760D03*
Y422240D03*
X237937Y390000D03*
X230063Y386260D03*
Y393740D03*
X253294Y394747D03*
X261168Y391007D03*
Y398487D03*
G54D46*
X116500Y78889D03*
Y83711D03*
G54D55*
X153237Y58583D03*
X165048Y52677D03*
X161111Y58583D03*
X168985D03*
X182764Y52677D03*
X172922D03*
X176859Y58583D03*
X184733D03*
G54D19*
X23819Y339154D03*
Y349154D03*
Y359154D03*
Y369154D03*
Y379154D03*
Y389154D03*
Y399154D03*
X65709Y52244D03*
X75709Y42244D03*
Y52244D03*
X95709Y42244D03*
X85709D03*
X95709Y52244D03*
X85709D03*
G54D29*
X62550Y349850D03*
G54D38*
X70313Y354280D03*
X73463D03*
X70313Y357429D03*
X73463D03*
X70312Y351130D03*
X73462D03*
X76589Y370000D03*
X70312Y373177D03*
X73462D03*
X70312Y376327D03*
X73462D03*
X79739Y370000D03*
X98659Y351130D03*
X101809D03*
Y354280D03*
X104959D03*
X103425Y357500D03*
X106575D03*
X93711Y374528D03*
X96861D03*
X94425Y367500D03*
X97575D03*
X94425Y371000D03*
X97575D03*
G54D47*
X125100Y75091D03*
Y86509D03*
G54D56*
X151420Y432880D03*
X204056Y128935D03*
X261800Y107300D03*
X261700Y114700D03*
G54D65*
X189300Y148400D03*
X219600Y147000D03*
G54D39*
X76664Y376425D03*
X76612Y363729D03*
Y366879D03*
X76664Y379575D03*
X70332Y379457D03*
Y382607D03*
X83864Y362325D03*
Y365475D03*
X79852Y363825D03*
Y366975D03*
X104958Y347981D03*
Y351131D03*
X98664Y382625D03*
Y385775D03*
G54D48*
X122156Y141343D03*
Y154257D03*
X113000Y141500D03*
Y154414D03*
G54D66*
X227510Y57613D03*
X234990D03*
X231250Y65487D03*
X294157Y376023D03*
X297897Y383897D03*
X290417D03*
X308486Y378422D03*
X312226Y386296D03*
X304746D03*
G54D57*
X155205Y52677D03*
G54D58*
X166895Y291162D03*
X175713Y287225D03*
Y295099D03*
G54D67*
X286549Y103090D03*
Y105649D03*
Y108209D03*
Y110768D03*
X309935Y103090D03*
Y105649D03*
Y108209D03*
Y110768D03*
G54D49*
X122000Y269437D03*
X119441D03*
Y261563D03*
X122000D03*
X124559Y269437D03*
Y261563D03*
X137059Y269437D03*
X134500D03*
X131941D03*
Y261563D03*
X134500D03*
X137059D03*
G54D68*
X316659Y266511D03*
X311541D03*
X316659Y274089D03*
X314100D03*
X311541D03*
G54D59*
X156220Y359838D03*
X158189D03*
X160157D03*
X162126D03*
X164094D03*
X166063D03*
Y368500D03*
X164094D03*
X162126D03*
X160157D03*
X158189D03*
X156220D03*
X168031Y359838D03*
X170000D03*
Y368500D03*
X168031D03*
G54D69*
X320000Y396000D03*
Y403000D03*
X327000Y396000D03*
Y403000D03*
M02*
